FILE_TYPE = MACRO_DRAWING;
SET COLOR_WIRE YELLOW;
SET COLOR_PROP ORANGE;
SET COLOR_DOT WHITE;
SET COLOR_ARC YELLOW;
SET COLOR_BODY GREEN;
SET COLOR_NOTE PURPLE;
SET PROP_DISPLAY VALUE;
SET PAGE_NUMBER P324;
FORCEADD OFFPAGE..1
(-4400 -2650);
PAINT AQUA (-4400 -2650);
FORCEPROP 2 LAST $XR2 147 
J 0
(-4621 -2722);
DISPLAY 0.638298 (-4621 -2722);
PAINT MONO (-4621 -2722);
FORCEPROP 2 LAST $XR1 83 
J 0
(-4621 -2686);
DISPLAY 0.638298 (-4621 -2686);
PAINT MONO (-4621 -2686);
FORCEPROP 2 LAST $XR0 81 
J 0
(-4621 -2650);
DISPLAY 0.638298 (-4621 -2650);
PAINT MONO (-4621 -2650);
FORCEPROP 2 LAST CDS_LIB standard
J 0
(-4400 -2650);
DISPLAY INVISIBLE (-4400 -2650);
FORCEPROP 1 LAST OFFPAGE TRUE
J 0
(-4075 -2775);
DISPLAY 0.872340 (-4075 -2775);
PAINT AQUA (-4075 -2775);
DISPLAY INVISIBLE (-4075 -2775);
FORCEPROP 1 LAST COMMENT_BODY TRUE
J 0
(-4275 -2750);
DISPLAY 0.872340 (-4275 -2750);
PAINT GREEN (-4275 -2750);
DISPLAY INVISIBLE (-4275 -2750);
FORCEPROP 2 LAST PATH I1
J 0
(-4350 -2575);
DISPLAY 0.680851 (-4350 -2575);
DISPLAY INVISIBLE (-4350 -2575);
FORCEADD GND..1
(-3000 -700);
FORCEPROP 3 LASTPIN (-3000 -650) SIG_NAME GND\g
J 0
(-2990 -640);
DISPLAY 0.659574 (-2990 -640);
PAINT MONO (-2990 -640);
DISPLAY INVISIBLE (-2990 -640);
FORCEPROP 2 LAST CDS_LIB pure_quanta_power
J 0
(-3000 -700);
DISPLAY INVISIBLE (-3000 -700);
FORCEPROP 1 LAST SIZE 1B
J 0
(-2925 -750);
DISPLAY 0.872340 (-2925 -750);
PAINT GREEN (-2925 -750);
DISPLAY INVISIBLE (-2925 -750);
FORCEPROP 1 LAST HDL_POWER GND
J 0
(-3000 -550);
DISPLAY 0.872340 (-3000 -550);
PAINT GREEN (-3000 -550);
DISPLAY INVISIBLE (-3000 -550);
FORCEPROP 1 LAST PATH I10
J 0
(-2925 -700);
DISPLAY 0.872340 (-2925 -700);
PAINT AQUA (-2925 -700);
DISPLAY INVISIBLE (-2925 -700);
FORCEADD Q_RES..2
(-3000 -475);
FORCEPROP 1 LAST LOCATION R4073
J 0
(-2955 -350);
DISPLAY 0.978723 (-2955 -350);
FORCEPROP 0 LAST $SEC 1
J 0
(-2950 -300);
DISPLAY 0.680851 (-2950 -300);
PAINT MONO (-2950 -300);
DISPLAY INVISIBLE (-2950 -300);
FORCEPROP 0 LAST CDS_SEC 1
J 0
(-2950 -300);
DISPLAY 1.021277 (-2950 -300);
DISPLAY INVISIBLE (-2950 -300);
FORCEPROP 1 LASTPIN (-3000 -375) $PN 1
J 0
(-2995 -413);
DISPLAY 0.787234 (-2995 -413);
PAINT MONO (-2995 -413);
FORCEPROP 1 LASTPIN (-3000 -575) $PN 2
J 0
(-2995 -565);
DISPLAY 0.787234 (-2995 -565);
PAINT MONO (-2995 -565);
FORCEPROP 0 LAST ROOM E1S_P12V_MAM_TIC_BOM1
J 0
(-2950 -650);
DISPLAY 0.553191 (-2950 -650);
PAINT RED (-2950 -650);
FORCEPROP 1 LAST TOLERANCE 5%
J 0
(-2950 -450);
DISPLAY 0.638298 (-2950 -450);
FORCEPROP 1 LAST VALUE 4.7K
J 0
(-2955 -400);
DISPLAY 0.638298 (-2955 -400);
FORCEPROP 1 LAST PACK_TYPE 0402LF
J 0
(-2960 -600);
DISPLAY 0.638298 (-2960 -600);
FORCEPROP 1 LAST WATTAGE 1/16W
J 0
(-2960 -500);
DISPLAY 0.638298 (-2960 -500);
FORCEPROP 1 LAST MATERIAL CHIP
J 0
(-2960 -550);
DISPLAY 0.638298 (-2960 -550);
FORCEPROP 2 LAST CDS_LIB pure_quanta
J 0
(-3000 -475);
DISPLAY INVISIBLE (-3000 -475);
FORCEPROP 1 LAST PART_NUMBER CS24702JB10
J 0
(-2960 -650);
DISPLAY 0.638298 (-2960 -650);
DISPLAY INVISIBLE (-2960 -650);
FORCEPROP 1 LAST PATH I11
J 0
(-2950 -300);
DISPLAY 0.978723 (-2950 -300);
PAINT WHITE (-2950 -300);
DISPLAY INVISIBLE (-2950 -300);
FORCEADD MOSFET_NCH_DUAL..1
(-2550 -100);
FORCEPROP 1 LAST LOCATION Q127
J 0
(-2399 -126);
DISPLAY 0.723404 (-2399 -126);
PAINT GREEN (-2399 -126);
FORCEPROP 0 LAST $SEC 1
J 0
(-2375 25);
DISPLAY 0.680851 (-2375 25);
PAINT MONO (-2375 25);
DISPLAY INVISIBLE (-2375 25);
FORCEPROP 0 LAST CDS_SEC 1
J 0
(-2375 25);
DISPLAY 1.021277 (-2375 25);
DISPLAY INVISIBLE (-2375 25);
FORCEPROP 0 LASTPIN (-2500 100) $PN 6
R 1
J 0
(-2510 110);
DISPLAY 0.680851 (-2510 110);
PAINT MONO (-2510 110);
FORCEPROP 0 LASTPIN (-2750 -150) $PN 2
J 2
(-2760 -140);
DISPLAY 0.680851 (-2760 -140);
PAINT MONO (-2760 -140);
FORCEPROP 0 LASTPIN (-2500 -300) $PN 1
R 1
J 2
(-2510 -310);
DISPLAY 0.680851 (-2510 -310);
PAINT MONO (-2510 -310);
FORCEPROP 2 LAST PART_TYPE SMLF
J 0
(-2375 -25);
DISPLAY 1.021277 (-2375 -25);
FORCEPROP 1 LAST MATERIAL IC
J 0
(-2399 -251);
DISPLAY 0.723404 (-2399 -251);
PAINT GREEN (-2399 -251);
FORCEPROP 2 LAST VALUE PJT138K
J 0
(-2375 -75);
DISPLAY 1.021277 (-2375 -75);
FORCEPROP 0 LAST ROOM E1S_P12V_MAM_TIC_BOM1
J 0
(-2400 -300);
DISPLAY 0.553191 (-2400 -300);
PAINT RED (-2400 -300);
FORCEPROP 1 LAST NEEDS_NO_SIZE TRUE
J 0
(-2550 -101);
DISPLAY 0.468085 (-2550 -101);
PAINT GREEN (-2550 -101);
DISPLAY INVISIBLE (-2550 -101);
FORCEPROP 1 LAST CDS_LMAN_SYM_OUTLINE -150,150,150,-150
J 0
(-2550 -100);
DISPLAY 0.468085 (-2550 -100);
PAINT GREEN (-2550 -100);
DISPLAY INVISIBLE (-2550 -100);
FORCEPROP 2 LAST CDS_LIB pure_quanta
J 0
(-2550 -100);
DISPLAY INVISIBLE (-2550 -100);
FORCEPROP 1 LAST PART_NUMBER BAM138K0003
J 0
(-2399 -186);
DISPLAY 0.723404 (-2399 -186);
PAINT GREEN (-2399 -186);
DISPLAY INVISIBLE (-2399 -186);
FORCEPROP 1 LAST PATH I12
J 0
(-2550 -100);
DISPLAY 0.723404 (-2550 -100);
PAINT GREEN (-2550 -100);
DISPLAY INVISIBLE (-2550 -100);
FORCEADD GND..1
(-2500 -450);
FORCEPROP 3 LASTPIN (-2500 -400) SIG_NAME GND\g
J 0
(-2490 -390);
DISPLAY 0.659574 (-2490 -390);
PAINT MONO (-2490 -390);
DISPLAY INVISIBLE (-2490 -390);
FORCEPROP 2 LAST CDS_LIB pure_quanta_power
J 0
(-2500 -450);
DISPLAY INVISIBLE (-2500 -450);
FORCEPROP 1 LAST SIZE 1B
J 0
(-2425 -500);
DISPLAY 0.872340 (-2425 -500);
PAINT GREEN (-2425 -500);
DISPLAY INVISIBLE (-2425 -500);
FORCEPROP 1 LAST HDL_POWER GND
J 0
(-2500 -300);
DISPLAY 0.872340 (-2500 -300);
PAINT GREEN (-2500 -300);
DISPLAY INVISIBLE (-2500 -300);
FORCEPROP 1 LAST PATH I13
J 0
(-2425 -450);
DISPLAY 0.872340 (-2425 -450);
PAINT AQUA (-2425 -450);
DISPLAY INVISIBLE (-2425 -450);
FORCEADD GND..1
(-2050 -2575);
FORCEPROP 3 LASTPIN (-2050 -2525) SIG_NAME GND\g
J 0
(-2040 -2515);
DISPLAY 0.659574 (-2040 -2515);
PAINT MONO (-2040 -2515);
DISPLAY INVISIBLE (-2040 -2515);
FORCEPROP 2 LAST CDS_LIB pure_quanta_power
J 0
(-2050 -2575);
DISPLAY INVISIBLE (-2050 -2575);
FORCEPROP 1 LAST SIZE 1B
J 0
(-1975 -2625);
DISPLAY 0.872340 (-1975 -2625);
PAINT GREEN (-1975 -2625);
DISPLAY INVISIBLE (-1975 -2625);
FORCEPROP 1 LAST HDL_POWER GND
J 0
(-2050 -2425);
DISPLAY 0.872340 (-2050 -2425);
PAINT GREEN (-2050 -2425);
DISPLAY INVISIBLE (-2050 -2425);
FORCEPROP 1 LAST PATH I14
J 0
(-1975 -2575);
DISPLAY 0.872340 (-1975 -2575);
PAINT AQUA (-1975 -2575);
DISPLAY INVISIBLE (-1975 -2575);
FORCEADD GND..1
(-125 -2825);
FORCEPROP 3 LASTPIN (-125 -2775) SIG_NAME GND\g
J 0
(-115 -2765);
DISPLAY 0.659574 (-115 -2765);
PAINT MONO (-115 -2765);
DISPLAY INVISIBLE (-115 -2765);
FORCEPROP 1 LAST SIZE 1B
J 0
(-50 -2875);
DISPLAY 0.872340 (-50 -2875);
PAINT GREEN (-50 -2875);
DISPLAY INVISIBLE (-50 -2875);
FORCEPROP 2 LAST CDS_LIB pure_quanta_power
J 0
(-125 -2825);
DISPLAY INVISIBLE (-125 -2825);
FORCEPROP 1 LAST HDL_POWER GND
J 0
(-125 -2675);
DISPLAY 0.872340 (-125 -2675);
PAINT GREEN (-125 -2675);
DISPLAY INVISIBLE (-125 -2675);
FORCEPROP 1 LAST PATH I15
J 0
(-50 -2825);
DISPLAY 0.872340 (-50 -2825);
PAINT AQUA (-50 -2825);
DISPLAY INVISIBLE (-50 -2825);
FORCEADD Q_RES..2
(-125 -2575);
FORCEPROP 1 LAST LOCATION PR3965
J 0
(-75 -2500);
DISPLAY 0.638298 (-75 -2500);
FORCEPROP 0 LAST $SEC 1
J 0
(-75 -2450);
DISPLAY 0.680851 (-75 -2450);
PAINT MONO (-75 -2450);
DISPLAY INVISIBLE (-75 -2450);
FORCEPROP 0 LAST CDS_SEC 1
J 0
(-75 -2450);
DISPLAY 1.021277 (-75 -2450);
DISPLAY INVISIBLE (-75 -2450);
FORCEPROP 1 LASTPIN (-125 -2475) $PN 1
J 0
(-120 -2513);
DISPLAY 0.787234 (-120 -2513);
PAINT MONO (-120 -2513);
FORCEPROP 1 LASTPIN (-125 -2675) $PN 2
J 0
(-120 -2665);
DISPLAY 0.787234 (-120 -2665);
PAINT MONO (-120 -2665);
FORCEPROP 1 LAST WATTAGE 1/16W
J 0
(-75 -2575);
DISPLAY 0.404255 (-75 -2575);
FORCEPROP 0 LAST ROOM E1S_P3V3_BOM1
J 0
(-75 -2700);
DISPLAY 0.553191 (-75 -2700);
PAINT RED (-75 -2700);
FORCEPROP 1 LAST PACK_TYPE 0402LF
J 0
(-75 -2650);
DISPLAY 0.404255 (-75 -2650);
FORCEPROP 1 LAST VALUE 15K
J 0
(-75 -2525);
DISPLAY 0.404255 (-75 -2525);
FORCEPROP 1 LAST TOLERANCE 1%
J 0
(-75 -2550);
DISPLAY 0.404255 (-75 -2550);
FORCEPROP 1 LAST MATERIAL CHIP
J 0
(-75 -2600);
DISPLAY 0.404255 (-75 -2600);
FORCEPROP 2 LAST CDS_LIB pure_quanta
J 0
(-125 -2575);
DISPLAY INVISIBLE (-125 -2575);
FORCEPROP 1 LAST PART_NUMBER CS31502FB05
J 0
(-75 -2625);
DISPLAY 0.404255 (-75 -2625);
DISPLAY INVISIBLE (-75 -2625);
FORCEPROP 1 LAST PATH I16
J 0
(-75 -2400);
DISPLAY 0.978723 (-75 -2400);
PAINT WHITE (-75 -2400);
DISPLAY INVISIBLE (-75 -2400);
FORCEADD Q_RES..2
(-125 -2300);
FORCEPROP 1 LAST LOCATION PR3964
J 0
(-75 -2250);
DISPLAY 0.638298 (-75 -2250);
FORCEPROP 0 LAST $SEC 1
J 0
(-75 -2175);
DISPLAY 0.680851 (-75 -2175);
PAINT MONO (-75 -2175);
DISPLAY INVISIBLE (-75 -2175);
FORCEPROP 0 LAST CDS_SEC 1
J 0
(-75 -2175);
DISPLAY 1.021277 (-75 -2175);
DISPLAY INVISIBLE (-75 -2175);
FORCEPROP 1 LASTPIN (-125 -2200) $PN 1
J 0
(-120 -2238);
DISPLAY 0.787234 (-120 -2238);
PAINT MONO (-120 -2238);
FORCEPROP 1 LASTPIN (-125 -2400) $PN 2
J 0
(-120 -2390);
DISPLAY 0.787234 (-120 -2390);
PAINT MONO (-120 -2390);
FORCEPROP 1 LAST WATTAGE 1/16W
J 0
(-75 -2325);
DISPLAY 0.404255 (-75 -2325);
FORCEPROP 0 LAST ROOM E1S_P3V3_BOM1
J 0
(-75 -2200);
DISPLAY 0.553191 (-75 -2200);
PAINT RED (-75 -2200);
FORCEPROP 1 LAST TOLERANCE 1%
J 0
(-75 -2300);
DISPLAY 0.404255 (-75 -2300);
FORCEPROP 1 LAST VALUE 7.15K
J 0
(-75 -2275);
DISPLAY 0.404255 (-75 -2275);
FORCEPROP 1 LAST PACK_TYPE 0402LF
J 0
(-75 -2400);
DISPLAY 0.404255 (-75 -2400);
FORCEPROP 1 LAST MATERIAL CHIP
J 0
(-75 -2350);
DISPLAY 0.404255 (-75 -2350);
FORCEPROP 2 LAST CDS_LIB pure_quanta
J 0
(-125 -2300);
DISPLAY INVISIBLE (-125 -2300);
FORCEPROP 1 LAST PART_NUMBER CS27152FB03
J 0
(-75 -2375);
DISPLAY 0.404255 (-75 -2375);
DISPLAY INVISIBLE (-75 -2375);
FORCEPROP 1 LAST PATH I17
J 0
(-75 -2125);
DISPLAY 0.978723 (-75 -2125);
PAINT WHITE (-75 -2125);
DISPLAY INVISIBLE (-75 -2125);
FORCEADD Q_RES..1
(-600 -1950);
FORCEPROP 1 LAST LOCATION R3959
J 0
(-800 -1950);
DISPLAY 0.638298 (-800 -1950);
FORCEPROP 0 LAST $SEC 1
J 0
(-650 -1850);
DISPLAY 0.680851 (-650 -1850);
PAINT MONO (-650 -1850);
DISPLAY INVISIBLE (-650 -1850);
FORCEPROP 0 LAST CDS_SEC 1
J 0
(-650 -1850);
DISPLAY 1.021277 (-650 -1850);
DISPLAY INVISIBLE (-650 -1850);
FORCEPROP 1 LASTPIN (-700 -1950) $PN 1
J 0
(-688 -1938);
DISPLAY 0.787234 (-688 -1938);
PAINT MONO (-688 -1938);
FORCEPROP 1 LASTPIN (-500 -1950) $PN 2
J 0
(-538 -1938);
DISPLAY 0.787234 (-538 -1938);
PAINT MONO (-538 -1938);
FORCEPROP 1 LAST WATTAGE 1/16W
J 2
(-425 -2050);
DISPLAY 0.510638 (-425 -2050);
FORCEPROP 1 LAST TOLERANCE 5%
J 0
(-450 -1950);
DISPLAY 0.510638 (-450 -1950);
FORCEPROP 1 LAST VALUE 0
J 2
(-475 -1950);
DISPLAY 0.510638 (-475 -1950);
FORCEPROP 1 LAST PACK_TYPE 0402LF
J 0
(-375 -1950);
DISPLAY 0.510638 (-375 -1950);
FORCEPROP 1 LAST MATERIAL CHIP
J 0
(-675 -2050);
DISPLAY 0.510638 (-675 -2050);
FORCEPROP 0 LAST ROOM E1S_P3V3_BOM1
J 0
(-800 -1850);
DISPLAY 0.680851 (-800 -1850);
PAINT RED (-800 -1850);
FORCEPROP 2 LAST CDS_LIB pure_quanta
J 0
(-600 -1950);
DISPLAY INVISIBLE (-600 -1950);
FORCEPROP 1 LAST PART_NUMBER CS00002JB13
J 0
(-675 -2000);
DISPLAY 0.510638 (-675 -2000);
DISPLAY INVISIBLE (-675 -2000);
FORCEPROP 1 LAST PATH I18
J 0
(-650 -1800);
DISPLAY 0.978723 (-650 -1800);
PAINT WHITE (-650 -1800);
DISPLAY INVISIBLE (-650 -1800);
FORCEADD GND..1
(-475 -1600);
FORCEPROP 3 LASTPIN (-475 -1550) SIG_NAME GND\g
J 0
(-465 -1540);
DISPLAY 0.659574 (-465 -1540);
PAINT MONO (-465 -1540);
DISPLAY INVISIBLE (-465 -1540);
FORCEPROP 2 LAST CDS_LIB pure_quanta_power
J 0
(-475 -1600);
DISPLAY INVISIBLE (-475 -1600);
FORCEPROP 1 LAST SIZE 1B
J 0
(-400 -1650);
DISPLAY 0.872340 (-400 -1650);
PAINT GREEN (-400 -1650);
DISPLAY INVISIBLE (-400 -1650);
FORCEPROP 1 LAST HDL_POWER GND
J 0
(-475 -1450);
DISPLAY 0.872340 (-475 -1450);
PAINT GREEN (-475 -1450);
DISPLAY INVISIBLE (-475 -1450);
FORCEPROP 1 LAST PATH I19
J 0
(-400 -1600);
DISPLAY 0.872340 (-400 -1600);
PAINT AQUA (-400 -1600);
DISPLAY INVISIBLE (-400 -1600);
FORCEADD Q_RES..1
(-3650 -2650);
FORCEPROP 1 LAST LOCATION R4063
J 0
(-3800 -2650);
DISPLAY 0.638298 (-3800 -2650);
FORCEPROP 0 LAST $SEC 1
J 0
(-3575 -2575);
DISPLAY INVISIBLE (-3575 -2575);
FORCEPROP 0 LAST CDS_SEC 1
J 0
(-3575 -2575);
DISPLAY INVISIBLE (-3575 -2575);
FORCEPROP 1 LASTPIN (-3750 -2650) $PN 1
J 0
(-3738 -2638);
DISPLAY 0.787234 (-3738 -2638);
PAINT MONO (-3738 -2638);
DISPLAY INVISIBLE (-3738 -2638);
FORCEPROP 1 LASTPIN (-3550 -2650) $PN 2
J 0
(-3588 -2638);
DISPLAY 0.787234 (-3588 -2638);
PAINT MONO (-3588 -2638);
DISPLAY INVISIBLE (-3588 -2638);
FORCEPROP 1 LAST WATTAGE 1/16W
J 2
(-3450 -2775);
DISPLAY 0.595745 (-3450 -2775);
FORCEPROP 1 LAST MATERIAL CHIP
J 0
(-3775 -2775);
DISPLAY 0.595745 (-3775 -2775);
FORCEPROP 1 LAST TOLERANCE 5%
J 0
(-3475 -2650);
DISPLAY 0.595745 (-3475 -2650);
FORCEPROP 1 LAST PACK_TYPE 0402LF
J 0
(-3575 -2725);
DISPLAY 0.595745 (-3575 -2725);
FORCEPROP 1 LAST VALUE 0
J 2
(-3500 -2650);
DISPLAY 0.595745 (-3500 -2650);
FORCEPROP 0 LAST ROOM E1S_P3V3_BOM1
J 0
(-3825 -2575);
DISPLAY 0.680851 (-3825 -2575);
PAINT RED (-3825 -2575);
FORCEPROP 2 LAST CDS_LIB pure_quanta
J 0
(-3650 -2650);
DISPLAY INVISIBLE (-3650 -2650);
FORCEPROP 1 LAST PART_NUMBER CS00002JB13
J 0
(-3950 -2725);
DISPLAY 0.595745 (-3950 -2725);
DISPLAY INVISIBLE (-3950 -2725);
FORCEPROP 1 LAST PATH I2
J 0
(-3700 -2500);
DISPLAY 0.978723 (-3700 -2500);
PAINT WHITE (-3700 -2500);
DISPLAY INVISIBLE (-3700 -2500);
FORCEADD Q_CAP..1
(-475 -1325);
FORCEPROP 1 LAST LOCATION PC2208
J 0
(-425 -1250);
DISPLAY 0.638298 (-425 -1250);
FORCEPROP 0 LAST $SEC 1
J 0
(-420 -1183);
DISPLAY INVISIBLE (-420 -1183);
FORCEPROP 0 LAST CDS_SEC 1
J 0
(-420 -1183);
DISPLAY INVISIBLE (-420 -1183);
FORCEPROP 1 LASTPIN (-475 -1225) $PN 1
J 0
(-465 -1245);
DISPLAY 0.787234 (-465 -1245);
PAINT MONO (-465 -1245);
DISPLAY INVISIBLE (-465 -1245);
FORCEPROP 1 LASTPIN (-475 -1425) $PN 2
J 0
(-465 -1445);
DISPLAY 0.787234 (-465 -1445);
PAINT MONO (-465 -1445);
DISPLAY INVISIBLE (-465 -1445);
FORCEPROP 1 LAST PACK_TYPE C0402
J 0
(-425 -1350);
DISPLAY 0.510638 (-425 -1350);
FORCEPROP 1 LAST VALUE 1UF
J 0
(-425 -1275);
DISPLAY 0.510638 (-425 -1275);
FORCEPROP 1 LAST VOLTAGE 25V
J 0
(-425 -1300);
DISPLAY 0.510638 (-425 -1300);
FORCEPROP 1 LAST MATERIAL X6S
J 0
(-425 -1325);
DISPLAY 0.510638 (-425 -1325);
FORCEPROP 2 LAST CDS_LIB pure_quanta
J 0
(-475 -1325);
DISPLAY INVISIBLE (-475 -1325);
FORCEPROP 1 LAST TOLERANCE 10%
J 0
(-425 -1375);
DISPLAY 0.638298 (-425 -1375);
DISPLAY INVISIBLE (-425 -1375);
FORCEPROP 1 LAST PART_NUMBER CH5104KEB02
J 0
(-425 -1375);
DISPLAY 0.510638 (-425 -1375);
DISPLAY INVISIBLE (-425 -1375);
FORCEPROP 1 LAST PATH I20
J 0
(-425 -1175);
DISPLAY 0.978723 (-425 -1175);
PAINT WHITE (-425 -1175);
DISPLAY INVISIBLE (-425 -1175);
FORCEADD Q_RES..2
(-125 -1575);
FORCEPROP 1 LAST LOCATION PR3963
J 0
(-75 -1500);
DISPLAY 0.638298 (-75 -1500);
FORCEPROP 0 LAST $SEC 1
J 0
(-75 -1450);
DISPLAY 0.680851 (-75 -1450);
PAINT MONO (-75 -1450);
DISPLAY INVISIBLE (-75 -1450);
FORCEPROP 0 LAST CDS_SEC 1
J 0
(-75 -1450);
DISPLAY 1.021277 (-75 -1450);
DISPLAY INVISIBLE (-75 -1450);
FORCEPROP 1 LASTPIN (-125 -1475) $PN 1
J 0
(-120 -1513);
DISPLAY 0.787234 (-120 -1513);
PAINT MONO (-120 -1513);
FORCEPROP 1 LASTPIN (-125 -1675) $PN 2
J 0
(-120 -1665);
DISPLAY 0.787234 (-120 -1665);
PAINT MONO (-120 -1665);
FORCEPROP 0 LAST ROOM E1S_P3V3_BOM1
J 0
(-75 -1450);
DISPLAY 0.446809 (-75 -1450);
PAINT RED (-75 -1450);
FORCEPROP 1 LAST PACK_TYPE 0402LF
J 0
(-75 -1650);
DISPLAY 0.404255 (-75 -1650);
FORCEPROP 1 LAST MATERIAL CHIP
J 0
(-75 -1600);
DISPLAY 0.404255 (-75 -1600);
FORCEPROP 1 LAST WATTAGE 1/16W
J 0
(-75 -1575);
DISPLAY 0.404255 (-75 -1575);
FORCEPROP 1 LAST VALUE 25.5K
J 0
(-75 -1525);
DISPLAY 0.404255 (-75 -1525);
FORCEPROP 1 LAST TOLERANCE 1%
J 0
(-75 -1550);
DISPLAY 0.404255 (-75 -1550);
FORCEPROP 2 LAST CDS_LIB pure_quanta
J 0
(-125 -1575);
DISPLAY INVISIBLE (-125 -1575);
FORCEPROP 1 LAST PART_NUMBER CS32552FB06
J 0
(-75 -1625);
DISPLAY 0.404255 (-75 -1625);
DISPLAY INVISIBLE (-75 -1625);
FORCEPROP 1 LAST PATH I21
J 0
(-75 -1400);
DISPLAY 0.978723 (-75 -1400);
PAINT WHITE (-75 -1400);
DISPLAY INVISIBLE (-75 -1400);
FORCEADD UNIVERSAL_POWER..1
(-475 -975);
FORCEPROP 3 LASTPIN (-475 -1025) SIG_NAME P3V3_AUX\g
J 0
(-465 -1015);
DISPLAY 0.659574 (-465 -1015);
PAINT MONO (-465 -1015);
DISPLAY INVISIBLE (-465 -1015);
FORCEPROP 1 LAST HDL_POWER P3V3_AUX
J 1
(-475 -925);
DISPLAY 0.872340 (-475 -925);
PAINT GREEN (-475 -925);
FORCEPROP 2 LAST CDS_LIB pure_quanta_power
J 0
(-475 -975);
DISPLAY INVISIBLE (-475 -975);
FORCEPROP 1 LAST PATH I22
J 0
(-425 -950);
DISPLAY 0.872340 (-425 -950);
PAINT AQUA (-425 -950);
DISPLAY INVISIBLE (-425 -950);
FORCEADD OFFPAGE..1
(-4225 -150);
PAINT AQUA (-4225 -150);
FORCEPROP 2 LAST $XR2 147 
J 0
(-4656 -150);
DISPLAY 0.638298 (-4656 -150);
PAINT MONO (-4656 -150);
FORCEPROP 2 LAST $XR1 83 
J 0
(-4536 -150);
DISPLAY 0.638298 (-4536 -150);
PAINT MONO (-4536 -150);
FORCEPROP 2 LAST $XR0 81 
J 0
(-4446 -150);
DISPLAY 0.638298 (-4446 -150);
PAINT MONO (-4446 -150);
FORCEPROP 2 LAST CDS_LIB standard
J 0
(-4225 -150);
DISPLAY INVISIBLE (-4225 -150);
FORCEPROP 1 LAST OFFPAGE TRUE
J 0
(-3900 -275);
DISPLAY 0.872340 (-3900 -275);
PAINT AQUA (-3900 -275);
DISPLAY INVISIBLE (-3900 -275);
FORCEPROP 1 LAST COMMENT_BODY TRUE
J 0
(-4100 -250);
DISPLAY 0.872340 (-4100 -250);
PAINT GREEN (-4100 -250);
DISPLAY INVISIBLE (-4100 -250);
FORCEPROP 2 LAST PATH I23
J 0
(-4475 -100);
DISPLAY 0.680851 (-4475 -100);
DISPLAY INVISIBLE (-4475 -100);
FORCEADD Q_RES..1
(-3375 -150);
FORCEPROP 1 LAST LOCATION R4064
J 0
(-3600 -150);
DISPLAY 0.638298 (-3600 -150);
FORCEPROP 0 LAST $SEC 1
J 0
(-3300 -75);
DISPLAY INVISIBLE (-3300 -75);
FORCEPROP 0 LAST CDS_SEC 1
J 0
(-3300 -75);
DISPLAY INVISIBLE (-3300 -75);
FORCEPROP 1 LASTPIN (-3475 -150) $PN 1
J 0
(-3463 -138);
DISPLAY 0.787234 (-3463 -138);
PAINT MONO (-3463 -138);
DISPLAY INVISIBLE (-3463 -138);
FORCEPROP 1 LASTPIN (-3275 -150) $PN 2
J 0
(-3313 -138);
DISPLAY 0.787234 (-3313 -138);
PAINT MONO (-3313 -138);
DISPLAY INVISIBLE (-3313 -138);
FORCEPROP 1 LAST TOLERANCE 5%
J 0
(-3200 -150);
DISPLAY 0.595745 (-3200 -150);
FORCEPROP 1 LAST MATERIAL CHIP
J 0
(-3500 -275);
DISPLAY 0.595745 (-3500 -275);
FORCEPROP 1 LAST VALUE 0
J 2
(-3225 -150);
DISPLAY 0.595745 (-3225 -150);
FORCEPROP 1 LAST WATTAGE 1/16W
J 2
(-3175 -275);
DISPLAY 0.595745 (-3175 -275);
FORCEPROP 1 LAST PACK_TYPE 0402LF
J 0
(-3300 -225);
DISPLAY 0.595745 (-3300 -225);
FORCEPROP 0 LAST ROOM E1S_P12V_MAM_TIC_BOM1
J 0
(-3725 -325);
DISPLAY 0.553191 (-3725 -325);
PAINT RED (-3725 -325);
FORCEPROP 2 LAST CDS_LIB pure_quanta
J 0
(-3375 -150);
DISPLAY INVISIBLE (-3375 -150);
FORCEPROP 1 LAST PART_NUMBER CS00002JB13
J 0
(-3675 -225);
DISPLAY 0.595745 (-3675 -225);
DISPLAY INVISIBLE (-3675 -225);
FORCEPROP 1 LAST PATH I24
J 0
(-3425 0);
DISPLAY 0.978723 (-3425 0);
PAINT WHITE (-3425 0);
DISPLAY INVISIBLE (-3425 0);
FORCEADD Q_RES..2
(-2500 500);
FORCEPROP 1 LAST LOCATION R4074
J 0
(-2465 667);
DISPLAY 0.638298 (-2465 667);
FORCEPROP 0 LAST $SEC 1
J 0
(-2450 700);
DISPLAY 0.680851 (-2450 700);
PAINT MONO (-2450 700);
DISPLAY INVISIBLE (-2450 700);
FORCEPROP 0 LAST CDS_SEC 1
J 0
(-2450 700);
DISPLAY 1.021277 (-2450 700);
DISPLAY INVISIBLE (-2450 700);
FORCEPROP 1 LASTPIN (-2500 600) $PN 1
J 0
(-2495 562);
DISPLAY 0.787234 (-2495 562);
PAINT MONO (-2495 562);
FORCEPROP 1 LASTPIN (-2500 400) $PN 2
J 0
(-2495 410);
DISPLAY 0.787234 (-2495 410);
PAINT MONO (-2495 410);
FORCEPROP 1 LAST VALUE 10K
J 0
(-2465 617);
DISPLAY 0.638298 (-2465 617);
FORCEPROP 1 LAST TOLERANCE 1%
J 0
(-2465 567);
DISPLAY 0.638298 (-2465 567);
FORCEPROP 1 LAST WATTAGE 1/16W
J 0
(-2470 517);
DISPLAY 0.638298 (-2470 517);
FORCEPROP 1 LAST PACK_TYPE 0402LF
J 0
(-2470 367);
DISPLAY 0.638298 (-2470 367);
FORCEPROP 1 LAST MATERIAL CHIP
J 0
(-2470 467);
DISPLAY 0.638298 (-2470 467);
FORCEPROP 0 LAST ROOM E1S_P12V_MAM_TIC_BOM1
J 0
(-2450 725);
DISPLAY 0.553191 (-2450 725);
PAINT RED (-2450 725);
FORCEPROP 2 LAST CDS_LIB pure_quanta
J 0
(-2500 500);
DISPLAY INVISIBLE (-2500 500);
FORCEPROP 1 LAST PART_NUMBER CS31002FB08
J 0
(-2470 417);
DISPLAY 0.638298 (-2470 417);
DISPLAY INVISIBLE (-2470 417);
FORCEPROP 1 LAST PATH I25
J 0
(-2450 675);
DISPLAY 0.978723 (-2450 675);
PAINT WHITE (-2450 675);
DISPLAY INVISIBLE (-2450 675);
FORCEADD UNIVERSAL_POWER..1
(-2500 750);
FORCEPROP 3 LASTPIN (-2500 700) SIG_NAME P12V_AUX\g
J 0
(-2490 710);
DISPLAY 0.659574 (-2490 710);
PAINT MONO (-2490 710);
DISPLAY INVISIBLE (-2490 710);
FORCEPROP 1 LAST HDL_POWER P12V_AUX
J 1
(-2500 800);
DISPLAY 0.872340 (-2500 800);
PAINT GREEN (-2500 800);
FORCEPROP 2 LAST CDS_LIB pure_quanta_power
J 0
(-2500 750);
DISPLAY INVISIBLE (-2500 750);
FORCEPROP 1 LAST PATH I26
J 0
(-2450 775);
DISPLAY 0.872340 (-2450 775);
PAINT AQUA (-2450 775);
DISPLAY INVISIBLE (-2450 775);
FORCEADD MOSFET_NCH_DUAL..2
(-1850 275);
FORCEPROP 1 LAST LOCATION Q127
J 0
(-1699 251);
DISPLAY 0.723404 (-1699 251);
PAINT GREEN (-1699 251);
FORCEPROP 0 LAST $SEC 2
J 0
(-1675 400);
DISPLAY 0.680851 (-1675 400);
PAINT MONO (-1675 400);
DISPLAY INVISIBLE (-1675 400);
FORCEPROP 0 LAST CDS_SEC 2
J 0
(-1675 400);
DISPLAY 1.021277 (-1675 400);
DISPLAY INVISIBLE (-1675 400);
FORCEPROP 0 LASTPIN (-1800 475) $PN 3
R 1
J 0
(-1810 485);
DISPLAY 0.680851 (-1810 485);
PAINT MONO (-1810 485);
FORCEPROP 0 LASTPIN (-2050 225) $PN 5
J 2
(-2060 235);
DISPLAY 0.680851 (-2060 235);
PAINT MONO (-2060 235);
FORCEPROP 0 LASTPIN (-1800 75) $PN 4
R 1
J 2
(-1810 65);
DISPLAY 0.680851 (-1810 65);
PAINT MONO (-1810 65);
FORCEPROP 0 LAST ROOM E1S_P12V_MAM_TIC_BOM1
J 0
(-1675 450);
DISPLAY 0.680851 (-1675 450);
PAINT RED (-1675 450);
FORCEPROP 2 LAST VALUE PJT138K
J 0
(-1675 300);
DISPLAY 1.021277 (-1675 300);
FORCEPROP 2 LAST PART_TYPE SMLF
J 0
(-1675 350);
DISPLAY 1.021277 (-1675 350);
FORCEPROP 1 LAST MATERIAL IC
J 0
(-1699 126);
DISPLAY 0.723404 (-1699 126);
PAINT GREEN (-1699 126);
FORCEPROP 1 LAST NEEDS_NO_SIZE TRUE
J 0
(-1700 166);
DISPLAY 0.468085 (-1700 166);
PAINT GREEN (-1700 166);
DISPLAY INVISIBLE (-1700 166);
FORCEPROP 1 LAST CDS_LMAN_SYM_OUTLINE -150,150,150,-150
J 0
(-1850 275);
DISPLAY 0.468085 (-1850 275);
PAINT GREEN (-1850 275);
DISPLAY INVISIBLE (-1850 275);
FORCEPROP 2 LAST CDS_LIB pure_quanta
J 0
(-1850 275);
DISPLAY INVISIBLE (-1850 275);
FORCEPROP 1 LAST PART_NUMBER BAM138K0003
J 0
(-1699 181);
DISPLAY 0.723404 (-1699 181);
PAINT GREEN (-1699 181);
DISPLAY INVISIBLE (-1699 181);
FORCEPROP 1 LAST PATH I27
J 0
(-1700 125);
DISPLAY 0.723404 (-1700 125);
PAINT GREEN (-1700 125);
DISPLAY INVISIBLE (-1700 125);
FORCEADD GND..1
(-1800 -75);
FORCEPROP 3 LASTPIN (-1800 -25) SIG_NAME GND\g
J 0
(-1790 -15);
DISPLAY 0.659574 (-1790 -15);
PAINT MONO (-1790 -15);
DISPLAY INVISIBLE (-1790 -15);
FORCEPROP 2 LAST CDS_LIB pure_quanta_power
J 0
(-1800 -75);
DISPLAY INVISIBLE (-1800 -75);
FORCEPROP 1 LAST SIZE 1B
J 0
(-1725 -125);
DISPLAY 0.872340 (-1725 -125);
PAINT GREEN (-1725 -125);
DISPLAY INVISIBLE (-1725 -125);
FORCEPROP 1 LAST HDL_POWER GND
J 0
(-1800 75);
DISPLAY 0.872340 (-1800 75);
PAINT GREEN (-1800 75);
DISPLAY INVISIBLE (-1800 75);
FORCEPROP 1 LAST PATH I28
J 0
(-1725 -75);
DISPLAY 0.872340 (-1725 -75);
PAINT AQUA (-1725 -75);
DISPLAY INVISIBLE (-1725 -75);
FORCEADD Q_RES..1
(-725 750);
FORCEPROP 1 LAST LOCATION R3958
J 0
(-775 800);
DISPLAY 0.978723 (-775 800);
FORCEPROP 0 LAST $SEC 1
J 0
(-775 850);
DISPLAY 0.680851 (-775 850);
PAINT MONO (-775 850);
DISPLAY INVISIBLE (-775 850);
FORCEPROP 0 LAST CDS_SEC 1
J 0
(-775 850);
DISPLAY 1.021277 (-775 850);
DISPLAY INVISIBLE (-775 850);
FORCEPROP 1 LASTPIN (-825 750) $PN 1
J 0
(-813 762);
DISPLAY 0.787234 (-813 762);
PAINT MONO (-813 762);
FORCEPROP 1 LASTPIN (-625 750) $PN 2
J 0
(-663 762);
DISPLAY 0.787234 (-663 762);
PAINT MONO (-663 762);
FORCEPROP 1 LAST MATERIAL CHIP
J 0
(-800 650);
DISPLAY 0.510638 (-800 650);
FORCEPROP 1 LAST TOLERANCE 5%
J 0
(-550 750);
DISPLAY 0.510638 (-550 750);
FORCEPROP 1 LAST PACK_TYPE 0402LF
J 0
(-450 750);
DISPLAY 0.510638 (-450 750);
FORCEPROP 1 LAST WATTAGE 1/16W
J 2
(-525 650);
DISPLAY 0.510638 (-525 650);
FORCEPROP 1 LAST VALUE 0
J 2
(-575 750);
DISPLAY 0.510638 (-575 750);
FORCEPROP 0 LAST ROOM E1S_P12V_MAM_TIC_BOM1
J 0
(-950 875);
DISPLAY 0.680851 (-950 875);
PAINT RED (-950 875);
FORCEPROP 2 LAST CDS_LIB pure_quanta
J 0
(-725 750);
DISPLAY INVISIBLE (-725 750);
FORCEPROP 1 LAST PART_NUMBER CS00002JB13
J 0
(-800 700);
DISPLAY 0.510638 (-800 700);
DISPLAY INVISIBLE (-800 700);
FORCEPROP 1 LAST PATH I29
J 0
(-775 900);
DISPLAY 0.978723 (-775 900);
PAINT WHITE (-775 900);
DISPLAY INVISIBLE (-775 900);
FORCEADD GND..1
(-3300 -3200);
FORCEPROP 3 LASTPIN (-3300 -3150) SIG_NAME GND\g
J 0
(-3290 -3140);
DISPLAY 0.659574 (-3290 -3140);
PAINT MONO (-3290 -3140);
DISPLAY INVISIBLE (-3290 -3140);
FORCEPROP 1 LAST SIZE 1B
J 0
(-3225 -3250);
DISPLAY 0.872340 (-3225 -3250);
PAINT GREEN (-3225 -3250);
DISPLAY INVISIBLE (-3225 -3250);
FORCEPROP 2 LAST CDS_LIB pure_quanta_power
J 0
(-3300 -3200);
DISPLAY INVISIBLE (-3300 -3200);
FORCEPROP 1 LAST HDL_POWER GND
J 0
(-3300 -3050);
DISPLAY 0.872340 (-3300 -3050);
PAINT GREEN (-3300 -3050);
DISPLAY INVISIBLE (-3300 -3050);
FORCEPROP 1 LAST PATH I3
J 0
(-3225 -3200);
DISPLAY 0.872340 (-3225 -3200);
PAINT AQUA (-3225 -3200);
DISPLAY INVISIBLE (-3225 -3200);
FORCEADD GND..1
(-125 -125);
FORCEPROP 3 LASTPIN (-125 -75) SIG_NAME GND\g
J 0
(-115 -65);
DISPLAY 0.659574 (-115 -65);
PAINT MONO (-115 -65);
DISPLAY INVISIBLE (-115 -65);
FORCEPROP 2 LAST CDS_LIB pure_quanta_power
J 0
(-125 -125);
DISPLAY INVISIBLE (-125 -125);
FORCEPROP 1 LAST SIZE 1B
J 0
(-50 -175);
DISPLAY 0.872340 (-50 -175);
PAINT GREEN (-50 -175);
DISPLAY INVISIBLE (-50 -175);
FORCEPROP 1 LAST HDL_POWER GND
J 0
(-125 25);
DISPLAY 0.872340 (-125 25);
PAINT GREEN (-125 25);
DISPLAY INVISIBLE (-125 25);
FORCEPROP 1 LAST PATH I30
J 0
(-50 -125);
DISPLAY 0.872340 (-50 -125);
PAINT AQUA (-50 -125);
DISPLAY INVISIBLE (-50 -125);
FORCEADD Q_RES..2
(-125 125);
FORCEPROP 1 LAST LOCATION PR3962
J 0
(-75 200);
DISPLAY 0.638298 (-75 200);
FORCEPROP 0 LAST $SEC 1
J 0
(-75 250);
DISPLAY 0.680851 (-75 250);
PAINT MONO (-75 250);
DISPLAY INVISIBLE (-75 250);
FORCEPROP 0 LAST CDS_SEC 1
J 0
(-75 250);
DISPLAY 1.021277 (-75 250);
DISPLAY INVISIBLE (-75 250);
FORCEPROP 1 LASTPIN (-125 225) $PN 1
J 0
(-120 187);
DISPLAY 0.787234 (-120 187);
PAINT MONO (-120 187);
FORCEPROP 1 LASTPIN (-125 25) $PN 2
J 0
(-120 35);
DISPLAY 0.787234 (-120 35);
PAINT MONO (-120 35);
FORCEPROP 0 LAST ROOM E1S_P12V_MAM_TIC_BOM1
J 0
(-75 0);
DISPLAY 0.446809 (-75 0);
PAINT RED (-75 0);
FORCEPROP 1 LAST VALUE 15K
J 0
(-75 175);
DISPLAY 0.404255 (-75 175);
FORCEPROP 1 LAST MATERIAL CHIP
J 0
(-75 100);
DISPLAY 0.404255 (-75 100);
FORCEPROP 1 LAST WATTAGE 1/16W
J 0
(-75 125);
DISPLAY 0.404255 (-75 125);
FORCEPROP 1 LAST PACK_TYPE 0402LF
J 0
(-75 50);
DISPLAY 0.404255 (-75 50);
FORCEPROP 1 LAST TOLERANCE 1%
J 0
(-75 150);
DISPLAY 0.404255 (-75 150);
FORCEPROP 2 LAST CDS_LIB pure_quanta
J 0
(-125 125);
DISPLAY INVISIBLE (-125 125);
FORCEPROP 1 LAST PART_NUMBER CS31502FB05
J 0
(-75 75);
DISPLAY 0.404255 (-75 75);
DISPLAY INVISIBLE (-75 75);
FORCEPROP 1 LAST PATH I31
J 0
(-75 300);
DISPLAY 0.978723 (-75 300);
PAINT WHITE (-75 300);
DISPLAY INVISIBLE (-75 300);
FORCEADD Q_RES..2
(-125 400);
FORCEPROP 1 LAST LOCATION PR3961
J 0
(-75 475);
DISPLAY 0.638298 (-75 475);
FORCEPROP 0 LAST $SEC 1
J 0
(-75 525);
DISPLAY 0.680851 (-75 525);
PAINT MONO (-75 525);
DISPLAY INVISIBLE (-75 525);
FORCEPROP 0 LAST CDS_SEC 1
J 0
(-75 525);
DISPLAY 1.021277 (-75 525);
DISPLAY INVISIBLE (-75 525);
FORCEPROP 1 LASTPIN (-125 500) $PN 1
J 0
(-120 462);
DISPLAY 0.787234 (-120 462);
PAINT MONO (-120 462);
FORCEPROP 1 LASTPIN (-125 300) $PN 2
J 0
(-120 310);
DISPLAY 0.787234 (-120 310);
PAINT MONO (-120 310);
FORCEPROP 1 LAST VALUE 6.8K
J 0
(-75 450);
DISPLAY 0.404255 (-75 450);
FORCEPROP 1 LAST TOLERANCE 1%
J 0
(-75 425);
DISPLAY 0.404255 (-75 425);
FORCEPROP 1 LAST WATTAGE 1/16W
J 0
(-75 400);
DISPLAY 0.404255 (-75 400);
FORCEPROP 1 LAST MATERIAL CHIP
J 0
(-75 375);
DISPLAY 0.404255 (-75 375);
FORCEPROP 1 LAST PACK_TYPE 0402LF
J 0
(-75 325);
DISPLAY 0.404255 (-75 325);
FORCEPROP 0 LAST ROOM E1S_P12V_MAM_TIC_BOM1
J 0
(-75 300);
DISPLAY 0.446809 (-75 300);
PAINT RED (-75 300);
FORCEPROP 2 LAST CDS_LIB pure_quanta
J 0
(-125 400);
DISPLAY INVISIBLE (-125 400);
FORCEPROP 1 LAST PART_NUMBER CS26802FB02
J 0
(-75 350);
DISPLAY 0.404255 (-75 350);
DISPLAY INVISIBLE (-75 350);
FORCEPROP 1 LAST PATH I32
J 0
(-75 575);
DISPLAY 0.978723 (-75 575);
PAINT WHITE (-75 575);
DISPLAY INVISIBLE (-75 575);
FORCEADD DIODE_TVS..1
R 1
(-900 1375);
FORCEPROP 1 LAST LOCATION PD114
J 0
(-845 1417);
DISPLAY 0.574468 (-845 1417);
PAINT GREEN (-845 1417);
FORCEPROP 0 LAST $SEC 1
R 1
J 0
(-825 1450);
DISPLAY 0.680851 (-825 1450);
PAINT MONO (-825 1450);
DISPLAY INVISIBLE (-825 1450);
FORCEPROP 0 LAST CDS_SEC 1
R 1
J 0
(-825 1450);
DISPLAY 1.021277 (-825 1450);
DISPLAY INVISIBLE (-825 1450);
FORCEPROP 0 LASTPIN (-900 1225) $PN A
R 1
J 2
(-910 1215);
DISPLAY 0.680851 (-910 1215);
PAINT MONO (-910 1215);
FORCEPROP 0 LASTPIN (-900 1525) $PN C
R 1
J 0
(-910 1535);
DISPLAY 0.680851 (-910 1535);
PAINT MONO (-910 1535);
FORCEPROP 2 LAST VALUE SMF14A
J 0
(-850 1350);
DISPLAY 0.574468 (-850 1350);
PAINT SKYBLUE (-850 1350);
FORCEPROP 1 LAST MATERIAL IC
J 0
(-825 1250);
DISPLAY 0.617021 (-825 1250);
PAINT GREEN (-825 1250);
FORCEPROP 2 LAST CDS_LIB pure_quanta
J 0
(-900 1375);
DISPLAY INVISIBLE (-900 1375);
FORCEPROP 1 LAST CDS_LMAN_SYM_OUTLINE -100,50,100,-50
R 1
J 0
(-900 1375);
DISPLAY 0.468085 (-900 1375);
PAINT GREEN (-900 1375);
DISPLAY INVISIBLE (-900 1375);
FORCEPROP 1 LASTPIN (-900 1525) Pin_Length Short
R 1
J 0
(-890 1550);
DISPLAY 0.489362 (-890 1550);
PAINT MONO (-890 1550);
DISPLAY INVISIBLE (-890 1550);
FORCEPROP 1 LAST PIN_NAMES_ROTATE TRUE
R 1
J 0
(-900 1375);
DISPLAY 0.489362 (-900 1375);
PAINT GREEN (-900 1375);
DISPLAY INVISIBLE (-900 1375);
FORCEPROP 0 LAST PART_TYPE SMLF
J 0
(-800 1500);
DISPLAY 1.021277 (-800 1500);
DISPLAY INVISIBLE (-800 1500);
FORCEPROP 1 LAST PART_NUMBER BCSMF14AZ01
J 0
(-845 1292);
DISPLAY 0.574468 (-845 1292);
PAINT GREEN (-845 1292);
DISPLAY INVISIBLE (-845 1292);
FORCEPROP 1 LAST PATH I33
R 1
J 0
(-850 1475);
DISPLAY 0.723404 (-850 1475);
PAINT GREEN (-850 1475);
DISPLAY INVISIBLE (-850 1475);
FORCEADD GND..1
(-700 1000);
FORCEPROP 3 LASTPIN (-700 1050) SIG_NAME GND\g
J 0
(-690 1060);
DISPLAY 0.659574 (-690 1060);
PAINT MONO (-690 1060);
DISPLAY INVISIBLE (-690 1060);
FORCEPROP 1 LAST SIZE 1B
J 0
(-625 950);
DISPLAY 0.872340 (-625 950);
PAINT GREEN (-625 950);
DISPLAY INVISIBLE (-625 950);
FORCEPROP 2 LAST CDS_LIB pure_quanta_power
J 0
(-700 1000);
DISPLAY INVISIBLE (-700 1000);
FORCEPROP 1 LAST HDL_POWER GND
J 0
(-700 1150);
DISPLAY 0.872340 (-700 1150);
PAINT GREEN (-700 1150);
DISPLAY INVISIBLE (-700 1150);
FORCEPROP 1 LAST PATH I34
J 0
(-625 1000);
DISPLAY 0.872340 (-625 1000);
PAINT AQUA (-625 1000);
DISPLAY INVISIBLE (-625 1000);
FORCEADD UNIVERSAL_POWER..1
(-700 1725);
FORCEPROP 3 LASTPIN (-700 1675) SIG_NAME P12V_AUX\g
J 0
(-690 1685);
DISPLAY 0.659574 (-690 1685);
PAINT MONO (-690 1685);
DISPLAY INVISIBLE (-690 1685);
FORCEPROP 1 LAST HDL_POWER P12V_AUX
J 1
(-700 1775);
DISPLAY 0.872340 (-700 1775);
PAINT GREEN (-700 1775);
FORCEPROP 2 LAST CDS_LIB pure_quanta_power
J 0
(-700 1725);
DISPLAY INVISIBLE (-700 1725);
FORCEPROP 1 LAST PATH I35
J 0
(-650 1750);
DISPLAY 0.872340 (-650 1750);
PAINT AQUA (-650 1750);
DISPLAY INVISIBLE (-650 1750);
FORCEADD Q_CAP..1
(-475 1375);
FORCEPROP 1 LAST LOCATION PC2207
J 0
(-425 1450);
DISPLAY 0.638298 (-425 1450);
FORCEPROP 0 LAST $SEC 1
J 0
(-420 1517);
DISPLAY INVISIBLE (-420 1517);
FORCEPROP 0 LAST CDS_SEC 1
J 0
(-420 1517);
DISPLAY INVISIBLE (-420 1517);
FORCEPROP 1 LASTPIN (-475 1475) $PN 1
J 0
(-465 1455);
DISPLAY 0.787234 (-465 1455);
PAINT MONO (-465 1455);
DISPLAY INVISIBLE (-465 1455);
FORCEPROP 1 LASTPIN (-475 1275) $PN 2
J 0
(-465 1255);
DISPLAY 0.787234 (-465 1255);
PAINT MONO (-465 1255);
DISPLAY INVISIBLE (-465 1255);
FORCEPROP 1 LAST PACK_TYPE C0402
J 0
(-425 1350);
DISPLAY 0.510638 (-425 1350);
FORCEPROP 1 LAST VOLTAGE 25V
J 0
(-425 1400);
DISPLAY 0.510638 (-425 1400);
FORCEPROP 1 LAST MATERIAL X6S
J 0
(-425 1375);
DISPLAY 0.510638 (-425 1375);
FORCEPROP 1 LAST VALUE 1UF
J 0
(-425 1425);
DISPLAY 0.510638 (-425 1425);
FORCEPROP 2 LAST CDS_LIB pure_quanta
J 0
(-475 1375);
DISPLAY INVISIBLE (-475 1375);
FORCEPROP 1 LAST TOLERANCE 10%
J 0
(-425 1325);
DISPLAY 0.638298 (-425 1325);
DISPLAY INVISIBLE (-425 1325);
FORCEPROP 1 LAST PART_NUMBER CH5104KEB02
J 0
(-425 1325);
DISPLAY 0.510638 (-425 1325);
DISPLAY INVISIBLE (-425 1325);
FORCEPROP 1 LAST PATH I36
J 0
(-425 1525);
DISPLAY 0.978723 (-425 1525);
PAINT WHITE (-425 1525);
DISPLAY INVISIBLE (-425 1525);
FORCEADD Q_RES..2
(-125 1075);
FORCEPROP 1 LAST LOCATION PR3960
J 0
(-75 1150);
DISPLAY 0.638298 (-75 1150);
FORCEPROP 0 LAST $SEC 1
J 0
(-75 1200);
DISPLAY 0.680851 (-75 1200);
PAINT MONO (-75 1200);
DISPLAY INVISIBLE (-75 1200);
FORCEPROP 0 LAST CDS_SEC 1
J 0
(-75 1200);
DISPLAY 1.021277 (-75 1200);
DISPLAY INVISIBLE (-75 1200);
FORCEPROP 1 LASTPIN (-125 1175) $PN 1
J 0
(-120 1137);
DISPLAY 0.787234 (-120 1137);
PAINT MONO (-120 1137);
FORCEPROP 1 LASTPIN (-125 975) $PN 2
J 0
(-120 985);
DISPLAY 0.787234 (-120 985);
PAINT MONO (-120 985);
FORCEPROP 1 LAST MATERIAL CHIP
J 0
(-75 1050);
DISPLAY 0.404255 (-75 1050);
FORCEPROP 1 LAST PACK_TYPE 0402LF
J 0
(-75 1000);
DISPLAY 0.404255 (-75 1000);
FORCEPROP 1 LAST TOLERANCE 1%
J 0
(-75 1100);
DISPLAY 0.404255 (-75 1100);
FORCEPROP 1 LAST WATTAGE 1/16W
J 0
(-75 1075);
DISPLAY 0.404255 (-75 1075);
FORCEPROP 1 LAST VALUE 160K
J 0
(-75 1125);
DISPLAY 0.404255 (-75 1125);
FORCEPROP 0 LAST ROOM E1S_P12V_MAM_TIC_BOM1
J 0
(-300 1200);
DISPLAY 0.446809 (-300 1200);
PAINT RED (-300 1200);
FORCEPROP 2 LAST CDS_LIB pure_quanta
J 0
(-125 1075);
DISPLAY INVISIBLE (-125 1075);
FORCEPROP 1 LAST PART_NUMBER CS41602FB05
J 0
(-75 1025);
DISPLAY 0.404255 (-75 1025);
DISPLAY INVISIBLE (-75 1025);
FORCEPROP 1 LAST PATH I37
J 0
(-75 1250);
DISPLAY 0.978723 (-75 1250);
PAINT WHITE (-75 1250);
DISPLAY INVISIBLE (-75 1250);
FORCEADD GND..1
(725 -2850);
FORCEPROP 3 LASTPIN (725 -2800) SIG_NAME GND\g
J 0
(735 -2790);
DISPLAY 0.659574 (735 -2790);
PAINT MONO (735 -2790);
DISPLAY INVISIBLE (735 -2790);
FORCEPROP 2 LAST CDS_LIB pure_quanta_power
J 0
(725 -2850);
DISPLAY INVISIBLE (725 -2850);
FORCEPROP 1 LAST SIZE 1B
J 0
(800 -2900);
DISPLAY 0.872340 (800 -2900);
PAINT GREEN (800 -2900);
DISPLAY INVISIBLE (800 -2900);
FORCEPROP 1 LAST HDL_POWER GND
J 0
(725 -2700);
DISPLAY 0.872340 (725 -2700);
PAINT GREEN (725 -2700);
DISPLAY INVISIBLE (725 -2700);
FORCEPROP 1 LAST PATH I38
J 0
(800 -2850);
DISPLAY 0.872340 (800 -2850);
PAINT AQUA (800 -2850);
DISPLAY INVISIBLE (800 -2850);
FORCEADD Q_RES..2
(725 -2550);
FORCEPROP 1 LAST LOCATION PR3969
J 0
(775 -2500);
DISPLAY 0.638298 (775 -2500);
FORCEPROP 0 LAST $SEC 1
J 0
(775 -2400);
DISPLAY 0.680851 (775 -2400);
PAINT MONO (775 -2400);
DISPLAY INVISIBLE (775 -2400);
FORCEPROP 0 LAST CDS_SEC 1
J 0
(775 -2425);
DISPLAY INVISIBLE (775 -2425);
FORCEPROP 1 LASTPIN (725 -2450) $PN 1
J 0
(730 -2488);
DISPLAY 0.787234 (730 -2488);
PAINT MONO (730 -2488);
FORCEPROP 1 LASTPIN (725 -2650) $PN 2
J 0
(730 -2640);
DISPLAY 0.787234 (730 -2640);
PAINT MONO (730 -2640);
FORCEPROP 0 LAST ROOM E1S_P3V3_BOM1
J 0
(375 -2625);
DISPLAY 0.553191 (375 -2625);
PAINT RED (375 -2625);
FORCEPROP 1 LAST MATERIAL CHIP
J 0
(775 -2600);
DISPLAY 0.510638 (775 -2600);
FORCEPROP 1 LAST WATTAGE 1/16W
J 0
(775 -2575);
DISPLAY 0.510638 (775 -2575);
FORCEPROP 1 LAST VALUE 2.49K
J 0
(775 -2525);
DISPLAY 0.510638 (775 -2525);
FORCEPROP 1 LAST TOLERANCE 1%
J 0
(775 -2550);
DISPLAY 0.510638 (775 -2550);
FORCEPROP 1 LAST PACK_TYPE 0402LF
J 0
(775 -2650);
DISPLAY 0.510638 (775 -2650);
FORCEPROP 2 LAST CDS_LIB pure_quanta
J 0
(725 -2550);
DISPLAY INVISIBLE (725 -2550);
FORCEPROP 1 LAST PART_NUMBER CS22492FB05
J 0
(775 -2625);
DISPLAY 0.510638 (775 -2625);
DISPLAY INVISIBLE (775 -2625);
FORCEPROP 1 LAST PATH I39
J 0
(775 -2375);
DISPLAY 0.978723 (775 -2375);
PAINT WHITE (775 -2375);
DISPLAY INVISIBLE (775 -2375);
FORCEADD Q_RES..2
(-3300 -2975);
FORCEPROP 1 LAST LOCATION R6049
J 0
(-3255 -2850);
DISPLAY 0.978723 (-3255 -2850);
FORCEPROP 0 LAST $SEC 1
J 0
(-3250 -2800);
DISPLAY 0.680851 (-3250 -2800);
PAINT MONO (-3250 -2800);
DISPLAY INVISIBLE (-3250 -2800);
FORCEPROP 0 LAST CDS_SEC 1
J 0
(-3250 -2800);
DISPLAY 1.021277 (-3250 -2800);
DISPLAY INVISIBLE (-3250 -2800);
FORCEPROP 1 LASTPIN (-3300 -2875) $PN 1
J 0
(-3295 -2913);
DISPLAY 0.787234 (-3295 -2913);
PAINT MONO (-3295 -2913);
FORCEPROP 1 LASTPIN (-3300 -3075) $PN 2
J 0
(-3295 -3065);
DISPLAY 0.787234 (-3295 -3065);
PAINT MONO (-3295 -3065);
FORCEPROP 1 LAST TOLERANCE 5%
J 0
(-3250 -2950);
DISPLAY 0.638298 (-3250 -2950);
FORCEPROP 1 LAST PACK_TYPE 0402LF
J 0
(-3260 -3100);
DISPLAY 0.638298 (-3260 -3100);
FORCEPROP 1 LAST MATERIAL CHIP
J 0
(-3260 -3050);
DISPLAY 0.638298 (-3260 -3050);
FORCEPROP 1 LAST VALUE 4.7K
J 0
(-3255 -2900);
DISPLAY 0.638298 (-3255 -2900);
FORCEPROP 1 LAST WATTAGE 1/16W
J 0
(-3260 -3000);
DISPLAY 0.638298 (-3260 -3000);
FORCEPROP 0 LAST ROOM E1S_P3V3_BOM1
J 0
(-3250 -2750);
DISPLAY 0.680851 (-3250 -2750);
PAINT RED (-3250 -2750);
FORCEPROP 2 LAST CDS_LIB pure_quanta
J 0
(-3300 -2975);
DISPLAY INVISIBLE (-3300 -2975);
FORCEPROP 1 LAST PART_NUMBER CS24702JB10
J 0
(-3260 -3150);
DISPLAY 0.638298 (-3260 -3150);
DISPLAY INVISIBLE (-3260 -3150);
FORCEPROP 1 LAST PATH I4
J 0
(-3250 -2800);
DISPLAY 0.978723 (-3250 -2800);
PAINT WHITE (-3250 -2800);
DISPLAY INVISIBLE (-3250 -2800);
FORCEADD GND..1
(200 -2125);
FORCEPROP 3 LASTPIN (200 -2075) SIG_NAME GND\g
J 0
(210 -2065);
DISPLAY 0.659574 (210 -2065);
PAINT MONO (210 -2065);
DISPLAY INVISIBLE (210 -2065);
FORCEPROP 2 LAST CDS_LIB pure_quanta_power
J 0
(200 -2125);
DISPLAY INVISIBLE (200 -2125);
FORCEPROP 1 LAST SIZE 1B
J 0
(275 -2175);
DISPLAY 0.872340 (275 -2175);
PAINT GREEN (275 -2175);
DISPLAY INVISIBLE (275 -2175);
FORCEPROP 1 LAST HDL_POWER GND
J 0
(200 -1975);
DISPLAY 0.872340 (200 -1975);
PAINT GREEN (200 -1975);
DISPLAY INVISIBLE (200 -1975);
FORCEPROP 1 LAST PATH I40
J 0
(275 -2125);
DISPLAY 0.872340 (275 -2125);
PAINT AQUA (275 -2125);
DISPLAY INVISIBLE (275 -2125);
FORCEADD Q_CAP..1
(200 -1750);
FORCEPROP 1 LAST LOCATION PC2210
J 0
(250 -1725);
DISPLAY 0.638298 (250 -1725);
FORCEPROP 0 LAST $SEC 1
J 0
(250 -1675);
DISPLAY 0.680851 (250 -1675);
PAINT MONO (250 -1675);
DISPLAY INVISIBLE (250 -1675);
FORCEPROP 0 LAST CDS_SEC 1
J 0
(250 -1675);
DISPLAY 1.021277 (250 -1675);
DISPLAY INVISIBLE (250 -1675);
FORCEPROP 1 LASTPIN (200 -1650) $PN 1
J 0
(210 -1670);
DISPLAY 0.787234 (210 -1670);
PAINT MONO (210 -1670);
FORCEPROP 1 LASTPIN (200 -1850) $PN 2
J 0
(210 -1870);
DISPLAY 0.787234 (210 -1870);
PAINT MONO (210 -1870);
FORCEPROP 0 LAST ROOM E1S_P3V3_BOM1
J 0
(250 -1625);
DISPLAY 0.446809 (250 -1625);
PAINT RED (250 -1625);
FORCEPROP 1 LAST PACK_TYPE C0402
J 0
(250 -1825);
DISPLAY 0.510638 (250 -1825);
FORCEPROP 1 LAST VOLTAGE 25V
J 0
(250 -1800);
DISPLAY 0.510638 (250 -1800);
FORCEPROP 1 LAST MATERIAL X6S
J 0
(250 -1775);
DISPLAY 0.510638 (250 -1775);
FORCEPROP 1 LAST VALUE 1UF
J 0
(250 -1750);
DISPLAY 0.510638 (250 -1750);
FORCEPROP 2 LAST CDS_LIB pure_quanta
J 0
(200 -1750);
DISPLAY INVISIBLE (200 -1750);
FORCEPROP 1 LAST TOLERANCE 10%
J 0
(250 -1800);
DISPLAY 0.638298 (250 -1800);
DISPLAY INVISIBLE (250 -1800);
FORCEPROP 1 LAST PART_NUMBER CH5104KEB02
J 0
(250 -1850);
DISPLAY 0.510638 (250 -1850);
DISPLAY INVISIBLE (250 -1850);
FORCEPROP 1 LAST PATH I41
J 0
(250 -1600);
DISPLAY 0.978723 (250 -1600);
PAINT WHITE (250 -1600);
DISPLAY INVISIBLE (250 -1600);
FORCEADD Q_CAP..1
R 1
(425 -2050);
FORCEPROP 1 LAST LOCATION PC2212
J 0
(250 -2000);
DISPLAY 0.638298 (250 -2000);
FORCEPROP 0 LAST $SEC 1
R 1
J 0
(250 -1950);
DISPLAY 0.680851 (250 -1950);
PAINT MONO (250 -1950);
DISPLAY INVISIBLE (250 -1950);
FORCEPROP 0 LAST CDS_SEC 1
R 1
J 0
(250 -1950);
DISPLAY 1.021277 (250 -1950);
DISPLAY INVISIBLE (250 -1950);
FORCEPROP 1 LASTPIN (325 -2050) $PN 1
R 1
J 0
(345 -2040);
DISPLAY 0.787234 (345 -2040);
PAINT MONO (345 -2040);
FORCEPROP 1 LASTPIN (525 -2050) $PN 2
R 1
J 0
(545 -2040);
DISPLAY 0.787234 (545 -2040);
PAINT MONO (545 -2040);
FORCEPROP 1 LAST PACK_TYPE C0402
J 0
(250 -2100);
DISPLAY 0.510638 (250 -2100);
FORCEPROP 1 LAST VALUE 1UF
J 0
(400 -2000);
DISPLAY 0.510638 (400 -2000);
FORCEPROP 1 LAST VOLTAGE 25V
J 0
(550 -2000);
DISPLAY 0.510638 (550 -2000);
FORCEPROP 0 LAST ROOM E1S_P3V3_BOM1
J 0
(250 -1950);
DISPLAY 0.446809 (250 -1950);
PAINT RED (250 -1950);
FORCEPROP 2 LAST CDS_LIB pure_quanta
J 0
(425 -2050);
DISPLAY INVISIBLE (425 -2050);
FORCEPROP 1 LAST MATERIAL X6S
R 1
J 0
(425 -2000);
DISPLAY 0.638298 (425 -2000);
DISPLAY INVISIBLE (425 -2000);
FORCEPROP 1 LAST TOLERANCE 10%
R 1
J 0
(475 -2000);
DISPLAY 0.638298 (475 -2000);
DISPLAY INVISIBLE (475 -2000);
FORCEPROP 1 LAST PART_NUMBER CH5104KEB02
J 0
(475 -2100);
DISPLAY 0.510638 (475 -2100);
DISPLAY INVISIBLE (475 -2100);
FORCEPROP 1 LAST PATH I42
R 1
J 0
(275 -2000);
DISPLAY 0.978723 (275 -2000);
PAINT WHITE (275 -2000);
DISPLAY INVISIBLE (275 -2000);
FORCEADD Q_RES..2
(200 -1325);
FORCEPROP 1 LAST LOCATION PR3967
J 0
(250 -1250);
DISPLAY 0.638298 (250 -1250);
FORCEPROP 0 LAST $SEC 1
J 0
(250 -1200);
DISPLAY 0.680851 (250 -1200);
PAINT MONO (250 -1200);
DISPLAY INVISIBLE (250 -1200);
FORCEPROP 0 LAST CDS_SEC 1
J 0
(250 -1200);
DISPLAY 1.021277 (250 -1200);
DISPLAY INVISIBLE (250 -1200);
FORCEPROP 1 LASTPIN (200 -1225) $PN 1
J 0
(205 -1263);
DISPLAY 0.787234 (205 -1263);
PAINT MONO (205 -1263);
FORCEPROP 1 LASTPIN (200 -1425) $PN 2
J 0
(205 -1415);
DISPLAY 0.787234 (205 -1415);
PAINT MONO (205 -1415);
FORCEPROP 1 LAST MATERIAL CHIP
J 0
(250 -1350);
DISPLAY 0.404255 (250 -1350);
FORCEPROP 1 LAST PACK_TYPE 0402LF
J 0
(250 -1400);
DISPLAY 0.404255 (250 -1400);
FORCEPROP 0 LAST ROOM E1S_P3V3_BOM1
J 0
(250 -1200);
DISPLAY 0.553191 (250 -1200);
PAINT RED (250 -1200);
FORCEPROP 1 LAST TOLERANCE 1%
J 0
(250 -1300);
DISPLAY 0.404255 (250 -1300);
FORCEPROP 1 LAST VALUE 10
J 0
(250 -1275);
DISPLAY 0.404255 (250 -1275);
FORCEPROP 1 LAST WATTAGE 1/16W
J 0
(250 -1325);
DISPLAY 0.404255 (250 -1325);
FORCEPROP 2 LAST CDS_LIB pure_quanta
J 0
(200 -1325);
DISPLAY INVISIBLE (200 -1325);
FORCEPROP 1 LAST PART_NUMBER CS01002FB07
J 0
(250 -1375);
DISPLAY 0.404255 (250 -1375);
DISPLAY INVISIBLE (250 -1375);
FORCEPROP 1 LAST PATH I43
J 0
(250 -1150);
DISPLAY 0.978723 (250 -1150);
PAINT WHITE (250 -1150);
DISPLAY INVISIBLE (250 -1150);
FORCEADD GND..1
(2200 -2725);
FORCEPROP 3 LASTPIN (2200 -2675) SIG_NAME GND\g
J 0
(2210 -2665);
DISPLAY 0.659574 (2210 -2665);
PAINT MONO (2210 -2665);
DISPLAY INVISIBLE (2210 -2665);
FORCEPROP 1 LAST SIZE 1B
J 0
(2275 -2775);
DISPLAY 0.872340 (2275 -2775);
PAINT GREEN (2275 -2775);
DISPLAY INVISIBLE (2275 -2775);
FORCEPROP 2 LAST CDS_LIB pure_quanta_power
J 0
(2200 -2725);
DISPLAY INVISIBLE (2200 -2725);
FORCEPROP 1 LAST HDL_POWER GND
J 0
(2200 -2575);
DISPLAY 0.872340 (2200 -2575);
PAINT GREEN (2200 -2575);
DISPLAY INVISIBLE (2200 -2575);
FORCEPROP 1 LAST PATH I44
J 0
(2275 -2725);
DISPLAY 0.872340 (2275 -2725);
PAINT AQUA (2275 -2725);
DISPLAY INVISIBLE (2275 -2725);
FORCEADD Q_RES..2
(2325 -2400);
FORCEPROP 1 LAST LOCATION PR3971
J 0
(2375 -2375);
DISPLAY 0.638298 (2375 -2375);
FORCEPROP 0 LAST $SEC 1
J 0
(2375 -2225);
DISPLAY 0.680851 (2375 -2225);
PAINT MONO (2375 -2225);
DISPLAY INVISIBLE (2375 -2225);
FORCEPROP 0 LAST CDS_SEC 1
J 0
(2375 -2225);
DISPLAY 1.021277 (2375 -2225);
DISPLAY INVISIBLE (2375 -2225);
FORCEPROP 1 LASTPIN (2325 -2300) $PN 1
J 0
(2330 -2338);
DISPLAY 0.787234 (2330 -2338);
PAINT MONO (2330 -2338);
FORCEPROP 1 LASTPIN (2325 -2500) $PN 2
J 0
(2330 -2490);
DISPLAY 0.787234 (2330 -2490);
PAINT MONO (2330 -2490);
FORCEPROP 0 LAST ROOM E1S_P3V3_BOM1
J 0
(2375 -2325);
DISPLAY 0.553191 (2375 -2325);
PAINT RED (2375 -2325);
FORCEPROP 1 LAST MATERIAL CHIP
J 0
(2375 -2475);
DISPLAY 0.404255 (2375 -2475);
FORCEPROP 1 LAST TOLERANCE 1%
J 0
(2375 -2425);
DISPLAY 0.404255 (2375 -2425);
FORCEPROP 1 LAST PACK_TYPE 0402LF
J 0
(2375 -2525);
DISPLAY 0.404255 (2375 -2525);
FORCEPROP 1 LAST VALUE 9.76K
J 0
(2375 -2400);
DISPLAY 0.404255 (2375 -2400);
FORCEPROP 1 LAST WATTAGE 1/16W
J 0
(2375 -2450);
DISPLAY 0.404255 (2375 -2450);
FORCEPROP 2 LAST CDS_LIB pure_quanta
J 0
(2325 -2400);
DISPLAY INVISIBLE (2325 -2400);
FORCEPROP 1 LAST PART_NUMBER CS29762FB05
J 0
(2375 -2500);
DISPLAY 0.404255 (2375 -2500);
DISPLAY INVISIBLE (2375 -2500);
FORCEPROP 1 LAST PATH I45
J 0
(2375 -2225);
DISPLAY 0.978723 (2375 -2225);
PAINT WHITE (2375 -2225);
DISPLAY INVISIBLE (2375 -2225);
FORCEADD Q_CAP..1
(2275 -1725);
FORCEPROP 1 LAST LOCATION PC2213
J 0
(2320 -1592);
DISPLAY 0.510638 (2320 -1592);
FORCEPROP 0 LAST $SEC 1
J 0
(2325 -1575);
DISPLAY 0.680851 (2325 -1575);
PAINT MONO (2325 -1575);
DISPLAY INVISIBLE (2325 -1575);
FORCEPROP 0 LAST CDS_SEC 1
J 0
(2325 -1575);
DISPLAY 1.021277 (2325 -1575);
DISPLAY INVISIBLE (2325 -1575);
FORCEPROP 1 LASTPIN (2275 -1625) $PN 1
J 0
(2285 -1645);
DISPLAY 0.787234 (2285 -1645);
PAINT MONO (2285 -1645);
FORCEPROP 1 LASTPIN (2275 -1825) $PN 2
J 0
(2285 -1845);
DISPLAY 0.787234 (2285 -1845);
PAINT MONO (2285 -1845);
FORCEPROP 1 LAST VALUE 0.01UF
J 0
(2320 -1642);
DISPLAY 0.404255 (2320 -1642);
FORCEPROP 0 LAST ROOM E1S_P3V3_BOM1
J 0
(2275 -1875);
DISPLAY 0.446809 (2275 -1875);
PAINT RED (2275 -1875);
FORCEPROP 1 LAST PACK_TYPE C0402
J 0
(2325 -1750);
DISPLAY 0.404255 (2325 -1750);
FORCEPROP 1 LAST VOLTAGE 50V
J 0
(2325 -1700);
DISPLAY 0.404255 (2325 -1700);
FORCEPROP 1 LAST MATERIAL EMPTY
J 0
(2325 -1850);
DISPLAY 0.638298 (2325 -1850);
PAINT RED (2325 -1850);
FORCEPROP 2 LAST CDS_LIB pure_quanta
J 0
(2275 -1725);
DISPLAY INVISIBLE (2275 -1725);
FORCEPROP 1 LAST TOLERANCE 10%
J 0
(2325 -1775);
DISPLAY 0.638298 (2325 -1775);
DISPLAY INVISIBLE (2325 -1775);
FORCEPROP 1 LAST PART_NUMBER CH31006KB18
J 0
(2325 -1800);
DISPLAY 0.404255 (2325 -1800);
DISPLAY INVISIBLE (2325 -1800);
FORCEPROP 1 LAST PATH I46
J 0
(2325 -1575);
DISPLAY 0.978723 (2325 -1575);
PAINT WHITE (2325 -1575);
DISPLAY INVISIBLE (2325 -1575);
FORCEADD Q_RES..2
(2550 -1725);
FORCEPROP 1 LAST LOCATION PR4527
J 0
(2595 -1600);
DISPLAY 0.978723 (2595 -1600);
FORCEPROP 0 LAST $SEC 1
J 0
(2600 -1550);
DISPLAY 0.680851 (2600 -1550);
PAINT MONO (2600 -1550);
DISPLAY INVISIBLE (2600 -1550);
FORCEPROP 0 LAST CDS_SEC 1
J 0
(2600 -1550);
DISPLAY 1.021277 (2600 -1550);
DISPLAY INVISIBLE (2600 -1550);
FORCEPROP 1 LASTPIN (2550 -1625) $PN 1
J 0
(2555 -1663);
DISPLAY 0.787234 (2555 -1663);
PAINT MONO (2555 -1663);
FORCEPROP 1 LASTPIN (2550 -1825) $PN 2
J 0
(2555 -1815);
DISPLAY 0.787234 (2555 -1815);
PAINT MONO (2555 -1815);
FORCEPROP 0 LAST ROOM E1S_P3V3_BOM1
J 0
(2600 -1500);
DISPLAY 0.680851 (2600 -1500);
PAINT RED (2600 -1500);
FORCEPROP 1 LAST TOLERANCE 1%
J 0
(2595 -1700);
DISPLAY 0.510638 (2595 -1700);
FORCEPROP 1 LAST WATTAGE 1/16W
J 0
(2590 -1750);
DISPLAY 0.510638 (2590 -1750);
FORCEPROP 1 LAST PACK_TYPE 0402LF
J 0
(2590 -1900);
DISPLAY 0.510638 (2590 -1900);
FORCEPROP 1 LAST VALUE 10M
J 0
(2595 -1650);
DISPLAY 0.510638 (2595 -1650);
FORCEPROP 1 LAST MATERIAL CHIP
J 0
(2590 -1800);
DISPLAY 0.510638 (2590 -1800);
FORCEPROP 2 LAST CDS_LIB pure_quanta
J 0
(2550 -1725);
DISPLAY INVISIBLE (2550 -1725);
FORCEPROP 1 LAST PART_NUMBER CS61002FB02
J 0
(2590 -1850);
DISPLAY 0.510638 (2590 -1850);
DISPLAY INVISIBLE (2590 -1850);
FORCEPROP 1 LAST PATH I47
J 0
(2600 -1550);
DISPLAY 0.978723 (2600 -1550);
PAINT WHITE (2600 -1550);
DISPLAY INVISIBLE (2600 -1550);
FORCEADD Q_RES..1
(2975 -2050);
FORCEPROP 1 LAST LOCATION R3973
J 0
(2575 -2050);
DISPLAY 0.638298 (2575 -2050);
FORCEPROP 0 LAST $SEC 1
J 0
(2925 -1975);
DISPLAY 0.680851 (2925 -1975);
PAINT MONO (2925 -1975);
DISPLAY INVISIBLE (2925 -1975);
FORCEPROP 0 LAST CDS_SEC 1
J 0
(2925 -1975);
DISPLAY 1.021277 (2925 -1975);
DISPLAY INVISIBLE (2925 -1975);
FORCEPROP 1 LASTPIN (2875 -2050) $PN 1
J 0
(2887 -2038);
DISPLAY 0.787234 (2887 -2038);
PAINT MONO (2887 -2038);
FORCEPROP 1 LASTPIN (3075 -2050) $PN 2
J 0
(3037 -2038);
DISPLAY 0.787234 (3037 -2038);
PAINT MONO (3037 -2038);
FORCEPROP 0 LAST ROOM E1S_P3V3_BOM1
J 0
(2800 -2125);
DISPLAY 0.553191 (2800 -2125);
PAINT RED (2800 -2125);
FORCEPROP 1 LAST VALUE 0
J 2
(3125 -2050);
DISPLAY 0.595745 (3125 -2050);
FORCEPROP 1 LAST TOLERANCE 5%
J 0
(3150 -2050);
DISPLAY 0.595745 (3150 -2050);
FORCEPROP 1 LAST MATERIAL CHIP
J 0
(2750 -2050);
DISPLAY 0.595745 (2750 -2050);
FORCEPROP 1 LAST WATTAGE 1/16W
J 2
(2775 -2100);
DISPLAY 0.595745 (2775 -2100);
FORCEPROP 1 LAST PACK_TYPE 0402LF
J 0
(3125 -2100);
DISPLAY 0.595745 (3125 -2100);
FORCEPROP 2 LAST CDS_LIB pure_quanta
J 0
(2975 -2050);
DISPLAY INVISIBLE (2975 -2050);
FORCEPROP 1 LAST PART_NUMBER CS00002JB13
J 0
(2800 -2100);
DISPLAY 0.595745 (2800 -2100);
DISPLAY INVISIBLE (2800 -2100);
FORCEPROP 1 LAST PATH I48
J 0
(2925 -1900);
DISPLAY 0.978723 (2925 -1900);
PAINT WHITE (2925 -1900);
DISPLAY INVISIBLE (2925 -1900);
FORCEADD Q_CAP..1
R 1
(3025 -1950);
FORCEPROP 1 LAST LOCATION PC2216
J 0
(2750 -1950);
DISPLAY 0.638298 (2750 -1950);
FORCEPROP 0 LAST $SEC 1
R 1
J 0
(3125 -1825);
DISPLAY 0.680851 (3125 -1825);
PAINT MONO (3125 -1825);
DISPLAY INVISIBLE (3125 -1825);
FORCEPROP 0 LAST CDS_SEC 1
R 1
J 0
(3125 -1825);
DISPLAY 1.021277 (3125 -1825);
DISPLAY INVISIBLE (3125 -1825);
FORCEPROP 1 LASTPIN (2925 -1950) $PN 1
R 1
J 0
(2945 -1940);
DISPLAY 0.787234 (2945 -1940);
PAINT MONO (2945 -1940);
FORCEPROP 1 LASTPIN (3125 -1950) $PN 2
R 1
J 0
(3145 -1940);
DISPLAY 0.787234 (3145 -1940);
PAINT MONO (3145 -1940);
FORCEPROP 0 LAST ROOM E1S_P3V3_BOM1
J 0
(2925 -1825);
DISPLAY 0.553191 (2925 -1825);
PAINT RED (2925 -1825);
FORCEPROP 1 LAST VALUE 6800PF
J 0
(2925 -1875);
DISPLAY 0.638298 (2925 -1875);
FORCEPROP 1 LAST PACK_TYPE C0402
J 0
(2800 -2000);
DISPLAY 0.638298 (2800 -2000);
FORCEPROP 1 LAST VOLTAGE 50V
J 0
(3125 -1875);
DISPLAY 0.638298 (3125 -1875);
FORCEPROP 1 LAST TOLERANCE 10%
R 1
J 0
(3075 -1900);
DISPLAY 0.638298 (3075 -1900);
DISPLAY INVISIBLE (3075 -1900);
FORCEPROP 1 LAST MATERIAL X7R
R 1
J 0
(3025 -1900);
DISPLAY 0.638298 (3025 -1900);
DISPLAY INVISIBLE (3025 -1900);
FORCEPROP 2 LAST CDS_LIB pure_quanta
R 1
J 0
(3025 -1950);
DISPLAY INVISIBLE (3025 -1950);
FORCEPROP 1 LAST PART_NUMBER CH2686K1B01
J 0
(3050 -1900);
DISPLAY 0.404255 (3050 -1900);
DISPLAY INVISIBLE (3050 -1900);
FORCEPROP 1 LAST PATH I49
R 1
J 0
(2875 -1900);
DISPLAY 0.978723 (2875 -1900);
PAINT WHITE (2875 -1900);
DISPLAY INVISIBLE (2875 -1900);
FORCEADD GND..1
(-2725 -2950);
FORCEPROP 3 LASTPIN (-2725 -2900) SIG_NAME GND\g
J 0
(-2715 -2890);
DISPLAY 0.659574 (-2715 -2890);
PAINT MONO (-2715 -2890);
DISPLAY INVISIBLE (-2715 -2890);
FORCEPROP 1 LAST SIZE 1B
J 0
(-2650 -3000);
DISPLAY 0.872340 (-2650 -3000);
PAINT GREEN (-2650 -3000);
DISPLAY INVISIBLE (-2650 -3000);
FORCEPROP 2 LAST CDS_LIB pure_quanta_power
J 0
(-2725 -2950);
DISPLAY INVISIBLE (-2725 -2950);
FORCEPROP 1 LAST HDL_POWER GND
J 0
(-2725 -2800);
DISPLAY 0.872340 (-2725 -2800);
PAINT GREEN (-2725 -2800);
DISPLAY INVISIBLE (-2725 -2800);
FORCEPROP 1 LAST PATH I5
J 0
(-2650 -2950);
DISPLAY 0.872340 (-2650 -2950);
PAINT AQUA (-2650 -2950);
DISPLAY INVISIBLE (-2650 -2950);
FORCEADD SCHOTTKY_AC..1
R 1
(2700 -1100);
FORCEPROP 1 LAST LOCATION PD113
J 0
(2750 -1075);
DISPLAY 0.723404 (2750 -1075);
PAINT GREEN (2750 -1075);
FORCEPROP 0 LAST $SEC 1
R 1
J 0
(2750 -1025);
DISPLAY INVISIBLE (2750 -1025);
FORCEPROP 0 LAST CDS_SEC 1
R 1
J 0
(2750 -1025);
DISPLAY INVISIBLE (2750 -1025);
FORCEPROP 0 LASTPIN (2700 -1225) $PN A
R 1
J 2
(2690 -1190);
DISPLAY 0.808511 (2690 -1190);
FORCEPROP 0 LASTPIN (2700 -975) $PN C
R 1
J 0
(2690 -1015);
DISPLAY 0.808511 (2690 -1015);
FORCEPROP 1 LAST MATERIAL IC
J 0
(2750 -1200);
DISPLAY 0.723404 (2750 -1200);
PAINT GREEN (2750 -1200);
FORCEPROP 2 LAST VALUE B340A-13-F
J 0
(2750 -1125);
DISPLAY 0.638298 (2750 -1125);
FORCEPROP 1 LAST NEEDS_NO_SIZE TRUE
R 1
J 0
(2750 -1025);
DISPLAY 0.468085 (2750 -1025);
PAINT GREEN (2750 -1025);
DISPLAY INVISIBLE (2750 -1025);
FORCEPROP 2 LAST CDS_LIB pure_quanta
R 1
J 0
(2700 -1100);
DISPLAY INVISIBLE (2700 -1100);
FORCEPROP 1 LAST CDS_LMAN_SYM_OUTLINE -75,50,75,-50
R 1
J 0
(2700 -1100);
DISPLAY 0.468085 (2700 -1100);
PAINT GREEN (2700 -1100);
DISPLAY INVISIBLE (2700 -1100);
FORCEPROP 0 LAST PART_TYPE SMLF
J 0
(2750 -925);
DISPLAY 1.021277 (2750 -925);
DISPLAY INVISIBLE (2750 -925);
FORCEPROP 1 LAST PART_NUMBER BC000340Z30
J 0
(2750 -1175);
DISPLAY 0.595745 (2750 -1175);
PAINT GREEN (2750 -1175);
DISPLAY INVISIBLE (2750 -1175);
FORCEPROP 1 LAST PATH I50
R 1
J 0
(2700 -1100);
DISPLAY 0.723404 (2700 -1100);
PAINT GREEN (2700 -1100);
DISPLAY INVISIBLE (2700 -1100);
FORCEADD GND..1
(3150 -2000);
FORCEPROP 3 LASTPIN (3150 -1950) SIG_NAME GND\g
J 0
(3160 -1940);
DISPLAY 0.659574 (3160 -1940);
PAINT MONO (3160 -1940);
DISPLAY INVISIBLE (3160 -1940);
FORCEPROP 1 LAST SIZE 1B
J 0
(3225 -2050);
DISPLAY 0.872340 (3225 -2050);
PAINT GREEN (3225 -2050);
DISPLAY INVISIBLE (3225 -2050);
FORCEPROP 2 LAST CDS_LIB pure_quanta_power
J 0
(3150 -2000);
DISPLAY INVISIBLE (3150 -2000);
FORCEPROP 1 LAST HDL_POWER GND
J 0
(3150 -1850);
DISPLAY 0.872340 (3150 -1850);
PAINT GREEN (3150 -1850);
DISPLAY INVISIBLE (3150 -1850);
FORCEPROP 1 LAST PATH I51
J 0
(3225 -2000);
DISPLAY 0.872340 (3225 -2000);
PAINT AQUA (3225 -2000);
DISPLAY INVISIBLE (3225 -2000);
FORCEADD Q_RES..2
(3325 -1750);
FORCEPROP 1 LAST LOCATION R3977
J 0
(3370 -1625);
DISPLAY 0.638298 (3370 -1625);
FORCEPROP 0 LAST $SEC 1
J 0
(3375 -1575);
DISPLAY 0.680851 (3375 -1575);
PAINT MONO (3375 -1575);
DISPLAY INVISIBLE (3375 -1575);
FORCEPROP 0 LAST CDS_SEC 1
J 0
(3375 -1575);
DISPLAY 1.021277 (3375 -1575);
DISPLAY INVISIBLE (3375 -1575);
FORCEPROP 1 LASTPIN (3325 -1650) $PN 1
J 0
(3330 -1688);
DISPLAY 0.787234 (3330 -1688);
PAINT MONO (3330 -1688);
FORCEPROP 1 LASTPIN (3325 -1850) $PN 2
J 0
(3330 -1840);
DISPLAY 0.787234 (3330 -1840);
PAINT MONO (3330 -1840);
FORCEPROP 1 LAST MATERIAL CHIP
J 0
(3365 -1825);
DISPLAY 0.510638 (3365 -1825);
FORCEPROP 1 LAST WATTAGE 1/16W
J 0
(3365 -1775);
DISPLAY 0.510638 (3365 -1775);
FORCEPROP 1 LAST TOLERANCE 1%
J 0
(3370 -1725);
DISPLAY 0.510638 (3370 -1725);
FORCEPROP 1 LAST VALUE 100K
J 0
(3370 -1675);
DISPLAY 0.510638 (3370 -1675);
FORCEPROP 0 LAST ROOM E1S_P3V3_BOM1
J 0
(3375 -1575);
DISPLAY 0.553191 (3375 -1575);
PAINT RED (3375 -1575);
FORCEPROP 1 LAST PACK_TYPE 0402LF
J 0
(3365 -1925);
DISPLAY 0.510638 (3365 -1925);
FORCEPROP 2 LAST CDS_LIB pure_quanta
J 0
(3325 -1750);
DISPLAY INVISIBLE (3325 -1750);
FORCEPROP 1 LAST PART_NUMBER CS41002FB09
J 0
(3365 -1875);
DISPLAY 0.510638 (3365 -1875);
DISPLAY INVISIBLE (3365 -1875);
FORCEPROP 1 LAST PATH I52
J 0
(3375 -1575);
DISPLAY 0.978723 (3375 -1575);
PAINT WHITE (3375 -1575);
DISPLAY INVISIBLE (3375 -1575);
FORCEADD VCCAUX15..1
(3525 -1425);
FORCEPROP 3 LASTPIN (3525 -1475) SIG_NAME P3V3_AUX\g
J 0
(3535 -1465);
DISPLAY 0.659574 (3535 -1465);
PAINT MONO (3535 -1465);
DISPLAY INVISIBLE (3535 -1465);
FORCEPROP 1 LAST HDL_POWER P3V3_AUX
J 1
(3525 -1375);
DISPLAY 0.723404 (3525 -1375);
PAINT GREEN (3525 -1375);
FORCEPROP 2 LAST CDS_LIB pure_quanta_power
J 0
(3525 -1425);
DISPLAY INVISIBLE (3525 -1425);
FORCEPROP 1 LAST PATH I53
J 0
(3575 -1400);
DISPLAY 0.872340 (3575 -1400);
PAINT AQUA (3575 -1400);
DISPLAY INVISIBLE (3575 -1400);
FORCEADD Q_RES..2
(3725 -1750);
FORCEPROP 1 LAST LOCATION R3979
J 0
(3770 -1625);
DISPLAY 0.638298 (3770 -1625);
FORCEPROP 0 LAST $SEC 1
J 0
(3775 -1575);
DISPLAY 0.680851 (3775 -1575);
PAINT MONO (3775 -1575);
DISPLAY INVISIBLE (3775 -1575);
FORCEPROP 0 LAST CDS_SEC 1
J 0
(3775 -1575);
DISPLAY 1.021277 (3775 -1575);
DISPLAY INVISIBLE (3775 -1575);
FORCEPROP 1 LASTPIN (3725 -1650) $PN 1
J 0
(3730 -1688);
DISPLAY 0.787234 (3730 -1688);
PAINT MONO (3730 -1688);
FORCEPROP 1 LASTPIN (3725 -1850) $PN 2
J 0
(3730 -1840);
DISPLAY 0.787234 (3730 -1840);
PAINT MONO (3730 -1840);
FORCEPROP 0 LAST ROOM E1S_P3V3_BOM1
J 0
(3775 -1575);
DISPLAY 0.553191 (3775 -1575);
PAINT RED (3775 -1575);
FORCEPROP 1 LAST WATTAGE 1/16W
J 0
(3765 -1775);
DISPLAY 0.510638 (3765 -1775);
FORCEPROP 1 LAST MATERIAL CHIP
J 0
(3765 -1825);
DISPLAY 0.510638 (3765 -1825);
FORCEPROP 1 LAST VALUE 100K
J 0
(3770 -1675);
DISPLAY 0.510638 (3770 -1675);
FORCEPROP 1 LAST PACK_TYPE 0402LF
J 0
(3765 -1925);
DISPLAY 0.510638 (3765 -1925);
FORCEPROP 1 LAST TOLERANCE 1%
J 0
(3770 -1725);
DISPLAY 0.510638 (3770 -1725);
FORCEPROP 2 LAST CDS_LIB pure_quanta
J 0
(3725 -1750);
DISPLAY INVISIBLE (3725 -1750);
FORCEPROP 1 LAST PART_NUMBER CS41002FB09
J 0
(3765 -1875);
DISPLAY 0.510638 (3765 -1875);
DISPLAY INVISIBLE (3765 -1875);
FORCEPROP 1 LAST PATH I54
J 0
(3775 -1575);
DISPLAY 0.978723 (3775 -1575);
PAINT WHITE (3775 -1575);
DISPLAY INVISIBLE (3775 -1575);
FORCEADD OFFPAGE..2
(4025 -2050);
PAINT AQUA (4025 -2050);
FORCEPROP 2 LAST $XR1 81 
J 0
(4334 -2050);
DISPLAY 0.638298 (4334 -2050);
PAINT MONO (4334 -2050);
FORCEPROP 2 LAST $XR0 147 
J 0
(4214 -2050);
DISPLAY 0.638298 (4214 -2050);
PAINT MONO (4214 -2050);
FORCEPROP 2 LAST CDS_LIB standard
J 0
(4025 -2050);
DISPLAY INVISIBLE (4025 -2050);
FORCEPROP 1 LAST OFFPAGE TRUE
J 0
(4350 -2175);
DISPLAY 0.872340 (4350 -2175);
PAINT AQUA (4350 -2175);
DISPLAY INVISIBLE (4350 -2175);
FORCEPROP 1 LAST COMMENT_BODY TRUE
J 0
(3980 -2145);
DISPLAY 0.872340 (3980 -2145);
PAINT GREEN (3980 -2145);
DISPLAY INVISIBLE (3980 -2145);
FORCEPROP 2 LAST PATH I55
J 0
(4200 -1975);
DISPLAY 0.680851 (4200 -1975);
DISPLAY INVISIBLE (4200 -1975);
FORCEADD GND..1
(3775 -1425);
FORCEPROP 3 LASTPIN (3775 -1375) SIG_NAME GND\g
J 0
(3785 -1365);
DISPLAY 0.659574 (3785 -1365);
PAINT MONO (3785 -1365);
DISPLAY INVISIBLE (3785 -1365);
FORCEPROP 1 LAST SIZE 1B
J 0
(3850 -1475);
DISPLAY 0.872340 (3850 -1475);
PAINT GREEN (3850 -1475);
DISPLAY INVISIBLE (3850 -1475);
FORCEPROP 2 LAST CDS_LIB pure_quanta_power
J 0
(3775 -1425);
DISPLAY INVISIBLE (3775 -1425);
FORCEPROP 1 LAST HDL_POWER GND
J 0
(3775 -1275);
DISPLAY 0.872340 (3775 -1275);
PAINT GREEN (3775 -1275);
DISPLAY INVISIBLE (3775 -1275);
FORCEPROP 1 LAST PATH I56
J 0
(3850 -1425);
DISPLAY 0.872340 (3850 -1425);
PAINT AQUA (3850 -1425);
DISPLAY INVISIBLE (3850 -1425);
FORCEADD Q_CAP..1
(3200 -1125);
FORCEPROP 1 LAST LOCATION PC2218
J 0
(3250 -1025);
DISPLAY 0.638298 (3250 -1025);
FORCEPROP 0 LAST $SEC 1
J 0
(3250 -975);
DISPLAY 0.680851 (3250 -975);
PAINT MONO (3250 -975);
DISPLAY INVISIBLE (3250 -975);
FORCEPROP 0 LAST CDS_SEC 1
J 0
(3250 -975);
DISPLAY 1.021277 (3250 -975);
DISPLAY INVISIBLE (3250 -975);
FORCEPROP 1 LASTPIN (3200 -1025) $PN 1
J 0
(3210 -1045);
DISPLAY 0.787234 (3210 -1045);
PAINT MONO (3210 -1045);
FORCEPROP 1 LASTPIN (3200 -1225) $PN 2
J 0
(3210 -1245);
DISPLAY 0.787234 (3210 -1245);
PAINT MONO (3210 -1245);
FORCEPROP 1 LAST PACK_TYPE 0402
J 0
(3250 -1225);
DISPLAY 0.638298 (3250 -1225);
FORCEPROP 1 LAST MATERIAL X7R
J 0
(3250 -1175);
DISPLAY 0.638298 (3250 -1175);
FORCEPROP 1 LAST VOLTAGE 25V
J 0
(3250 -1125);
DISPLAY 0.638298 (3250 -1125);
FORCEPROP 1 LAST VALUE 0.1UF
J 0
(3250 -1075);
DISPLAY 0.638298 (3250 -1075);
FORCEPROP 2 LAST CDS_LIB pure_quanta
J 0
(3200 -1125);
DISPLAY INVISIBLE (3200 -1125);
FORCEPROP 1 LAST TOLERANCE 10%
J 0
(3250 -1175);
DISPLAY 0.978723 (3250 -1175);
DISPLAY INVISIBLE (3250 -1175);
FORCEPROP 1 LAST PART_NUMBER CH4104K1B00
J 0
(3250 -1275);
DISPLAY 0.638298 (3250 -1275);
DISPLAY INVISIBLE (3250 -1275);
FORCEPROP 1 LAST PATH I57
J 0
(3250 -975);
DISPLAY 0.978723 (3250 -975);
PAINT WHITE (3250 -975);
DISPLAY INVISIBLE (3250 -975);
FORCEADD Q_CAP..1
(3775 -1125);
FORCEPROP 1 LAST LOCATION PC2220
J 0
(3825 -1025);
DISPLAY 0.680851 (3825 -1025);
FORCEPROP 0 LAST $SEC 1
J 0
(3825 -975);
DISPLAY INVISIBLE (3825 -975);
FORCEPROP 0 LAST CDS_SEC 1
J 0
(3825 -975);
DISPLAY INVISIBLE (3825 -975);
FORCEPROP 1 LASTPIN (3775 -1025) $PN 1
J 0
(3785 -1045);
DISPLAY 0.787234 (3785 -1045);
PAINT MONO (3785 -1045);
DISPLAY INVISIBLE (3785 -1045);
FORCEPROP 1 LASTPIN (3775 -1225) $PN 2
J 0
(3785 -1245);
DISPLAY 0.787234 (3785 -1245);
PAINT MONO (3785 -1245);
DISPLAY INVISIBLE (3785 -1245);
FORCEPROP 1 LAST PACK_TYPE C0805
J 0
(3825 -1225);
DISPLAY 0.638298 (3825 -1225);
FORCEPROP 1 LAST MATERIAL X6S
J 0
(3825 -1175);
DISPLAY 0.638298 (3825 -1175);
FORCEPROP 1 LAST VALUE 10UF
J 0
(3825 -1075);
DISPLAY 0.638298 (3825 -1075);
FORCEPROP 1 LAST VOLTAGE 16V
J 0
(3825 -1125);
DISPLAY 0.638298 (3825 -1125);
FORCEPROP 1 LAST TOLERANCE 10%
J 0
(3564 -1165);
DISPLAY 0.787234 (3564 -1165);
PAINT GREEN (3564 -1165);
DISPLAY INVISIBLE (3564 -1165);
FORCEPROP 2 LAST CDS_LIB pure_quanta
J 0
(3775 -1125);
DISPLAY INVISIBLE (3775 -1125);
FORCEPROP 1 LAST PART_NUMBER CH6103KEA01
J 0
(3825 -1275);
DISPLAY 0.638298 (3825 -1275);
DISPLAY INVISIBLE (3825 -1275);
FORCEPROP 1 LAST PATH I58
J 0
(3825 -975);
DISPLAY 0.978723 (3825 -975);
PAINT WHITE (3825 -975);
DISPLAY INVISIBLE (3825 -975);
FORCEADD UNIVERSAL_POWER..1
R 2
(3775 -825);
FORCEPROP 3 LASTPIN (3775 -875) SIG_NAME P3V3_E1S_0_R\g
J 0
(3785 -865);
DISPLAY 0.659574 (3785 -865);
PAINT MONO (3785 -865);
DISPLAY INVISIBLE (3785 -865);
FORCEPROP 1 LAST HDL_POWER P3V3_E1S_0_R
J 1
(3775 -775);
DISPLAY 0.723404 (3775 -775);
PAINT GREEN (3775 -775);
FORCEPROP 2 LAST CDS_LIB pure_quanta_power
J 0
(3775 -825);
DISPLAY INVISIBLE (3775 -825);
FORCEPROP 1 LAST PATH I59
J 2
(3725 -800);
DISPLAY 0.872340 (3725 -800);
PAINT AQUA (3725 -800);
DISPLAY INVISIBLE (3725 -800);
FORCEADD MOSFET_NCH_DUAL..1
(-2775 -2600);
FORCEPROP 1 LAST LOCATION Q126
J 0
(-2624 -2626);
DISPLAY 0.723404 (-2624 -2626);
PAINT GREEN (-2624 -2626);
FORCEPROP 0 LAST $SEC 1
J 0
(-2600 -2475);
DISPLAY 0.680851 (-2600 -2475);
PAINT MONO (-2600 -2475);
DISPLAY INVISIBLE (-2600 -2475);
FORCEPROP 0 LAST CDS_SEC 1
J 0
(-2600 -2475);
DISPLAY 1.021277 (-2600 -2475);
DISPLAY INVISIBLE (-2600 -2475);
FORCEPROP 0 LASTPIN (-2725 -2400) $PN 6
R 1
J 0
(-2735 -2390);
DISPLAY 0.680851 (-2735 -2390);
PAINT MONO (-2735 -2390);
FORCEPROP 0 LASTPIN (-2975 -2650) $PN 2
J 2
(-2935 -2590);
DISPLAY 0.680851 (-2935 -2590);
PAINT MONO (-2935 -2590);
FORCEPROP 0 LASTPIN (-2725 -2800) $PN 1
R 1
J 2
(-2735 -2810);
DISPLAY 0.680851 (-2735 -2810);
PAINT MONO (-2735 -2810);
FORCEPROP 1 LAST MATERIAL IC
J 0
(-2624 -2751);
DISPLAY 0.723404 (-2624 -2751);
PAINT GREEN (-2624 -2751);
FORCEPROP 2 LAST VALUE PJT138K
J 0
(-2600 -2575);
DISPLAY 1.021277 (-2600 -2575);
FORCEPROP 2 LAST PART_TYPE SMLF
J 0
(-2600 -2525);
DISPLAY 1.021277 (-2600 -2525);
FORCEPROP 0 LAST ROOM E1S_P3V3_BOM1
J 0
(-2600 -2450);
DISPLAY 0.553191 (-2600 -2450);
PAINT RED (-2600 -2450);
FORCEPROP 2 LAST CDS_LIB pure_quanta
J 0
(-2775 -2600);
DISPLAY INVISIBLE (-2775 -2600);
FORCEPROP 1 LAST CDS_LMAN_SYM_OUTLINE -150,150,150,-150
J 0
(-2775 -2600);
DISPLAY 0.468085 (-2775 -2600);
PAINT GREEN (-2775 -2600);
DISPLAY INVISIBLE (-2775 -2600);
FORCEPROP 1 LAST NEEDS_NO_SIZE TRUE
J 0
(-2775 -2601);
DISPLAY 0.468085 (-2775 -2601);
PAINT GREEN (-2775 -2601);
DISPLAY INVISIBLE (-2775 -2601);
FORCEPROP 1 LAST PART_NUMBER BAM138K0003
J 0
(-2624 -2686);
DISPLAY 0.723404 (-2624 -2686);
PAINT GREEN (-2624 -2686);
DISPLAY INVISIBLE (-2624 -2686);
FORCEPROP 1 LAST PATH I6
J 0
(-2775 -2600);
DISPLAY 0.723404 (-2775 -2600);
PAINT GREEN (-2775 -2600);
DISPLAY INVISIBLE (-2775 -2600);
FORCEADD GND..1
(200 575);
FORCEPROP 3 LASTPIN (200 625) SIG_NAME GND\g
J 0
(210 635);
DISPLAY 0.659574 (210 635);
PAINT MONO (210 635);
DISPLAY INVISIBLE (210 635);
FORCEPROP 2 LAST CDS_LIB pure_quanta_power
J 0
(200 575);
DISPLAY INVISIBLE (200 575);
FORCEPROP 1 LAST SIZE 1B
J 0
(275 525);
DISPLAY 0.872340 (275 525);
PAINT GREEN (275 525);
DISPLAY INVISIBLE (275 525);
FORCEPROP 1 LAST HDL_POWER GND
J 0
(200 725);
DISPLAY 0.872340 (200 725);
PAINT GREEN (200 725);
DISPLAY INVISIBLE (200 725);
FORCEPROP 1 LAST PATH I60
J 0
(275 575);
DISPLAY 0.872340 (275 575);
PAINT AQUA (275 575);
DISPLAY INVISIBLE (275 575);
FORCEADD Q_CAP..1
R 1
(425 650);
FORCEPROP 1 LAST LOCATION PC2211
J 0
(250 700);
DISPLAY 0.638298 (250 700);
FORCEPROP 0 LAST $SEC 1
R 1
J 0
(250 750);
DISPLAY 0.680851 (250 750);
PAINT MONO (250 750);
DISPLAY INVISIBLE (250 750);
FORCEPROP 0 LAST CDS_SEC 1
R 1
J 0
(250 750);
DISPLAY 1.021277 (250 750);
DISPLAY INVISIBLE (250 750);
FORCEPROP 1 LASTPIN (325 650) $PN 1
R 1
J 0
(345 660);
DISPLAY 0.787234 (345 660);
PAINT MONO (345 660);
FORCEPROP 1 LASTPIN (525 650) $PN 2
R 1
J 0
(545 660);
DISPLAY 0.787234 (545 660);
PAINT MONO (545 660);
FORCEPROP 1 LAST PACK_TYPE C0402
J 0
(250 600);
DISPLAY 0.510638 (250 600);
FORCEPROP 0 LAST ROOM E1S_P12V_MAM_TIC_BOM1
J 0
(150 750);
DISPLAY 0.361702 (150 750);
PAINT RED (150 750);
FORCEPROP 1 LAST VALUE 1UF
J 0
(400 700);
DISPLAY 0.510638 (400 700);
FORCEPROP 1 LAST VOLTAGE 25V
J 0
(575 700);
DISPLAY 0.510638 (575 700);
FORCEPROP 1 LAST TOLERANCE 10%
R 1
J 0
(475 700);
DISPLAY 0.638298 (475 700);
DISPLAY INVISIBLE (475 700);
FORCEPROP 1 LAST MATERIAL X6S
R 1
J 0
(425 700);
DISPLAY 0.638298 (425 700);
DISPLAY INVISIBLE (425 700);
FORCEPROP 2 LAST CDS_LIB pure_quanta
J 0
(425 650);
DISPLAY INVISIBLE (425 650);
FORCEPROP 1 LAST PART_NUMBER CH5104KEB02
J 0
(475 600);
DISPLAY 0.510638 (475 600);
DISPLAY INVISIBLE (475 600);
FORCEPROP 1 LAST PATH I61
R 1
J 0
(275 700);
DISPLAY 0.978723 (275 700);
PAINT WHITE (275 700);
DISPLAY INVISIBLE (275 700);
FORCEADD GND..1
(725 -150);
FORCEPROP 3 LASTPIN (725 -100) SIG_NAME GND\g
J 0
(735 -90);
DISPLAY 0.659574 (735 -90);
PAINT MONO (735 -90);
DISPLAY INVISIBLE (735 -90);
FORCEPROP 2 LAST CDS_LIB pure_quanta_power
J 0
(725 -150);
DISPLAY INVISIBLE (725 -150);
FORCEPROP 1 LAST SIZE 1B
J 0
(800 -200);
DISPLAY 0.872340 (800 -200);
PAINT GREEN (800 -200);
DISPLAY INVISIBLE (800 -200);
FORCEPROP 1 LAST HDL_POWER GND
J 0
(725 0);
DISPLAY 0.872340 (725 0);
PAINT GREEN (725 0);
DISPLAY INVISIBLE (725 0);
FORCEPROP 1 LAST PATH I62
J 0
(800 -150);
DISPLAY 0.872340 (800 -150);
PAINT AQUA (800 -150);
DISPLAY INVISIBLE (800 -150);
FORCEADD Q_RES..2
(725 150);
FORCEPROP 1 LAST LOCATION PR3968
J 0
(775 200);
DISPLAY 0.638298 (775 200);
FORCEPROP 0 LAST $SEC 1
J 0
(775 300);
DISPLAY 0.680851 (775 300);
PAINT MONO (775 300);
DISPLAY INVISIBLE (775 300);
FORCEPROP 0 LAST CDS_SEC 1
J 0
(775 275);
DISPLAY INVISIBLE (775 275);
FORCEPROP 1 LASTPIN (725 250) $PN 1
J 0
(730 212);
DISPLAY 0.787234 (730 212);
PAINT MONO (730 212);
FORCEPROP 1 LASTPIN (725 50) $PN 2
J 0
(730 60);
DISPLAY 0.787234 (730 60);
PAINT MONO (730 60);
FORCEPROP 0 LAST ROOM E1S_P12V_MAM_TIC_BOM1
J 0
(600 25);
DISPLAY 0.446809 (600 25);
PAINT RED (600 25);
FORCEPROP 1 LAST PACK_TYPE 0402LF
J 0
(775 50);
DISPLAY 0.510638 (775 50);
FORCEPROP 1 LAST MATERIAL CHIP
J 0
(775 100);
DISPLAY 0.510638 (775 100);
FORCEPROP 1 LAST WATTAGE 1/16W
J 0
(775 125);
DISPLAY 0.510638 (775 125);
FORCEPROP 1 LAST TOLERANCE 1%
J 0
(775 150);
DISPLAY 0.510638 (775 150);
FORCEPROP 1 LAST VALUE 9.31K
J 0
(775 175);
DISPLAY 0.510638 (775 175);
FORCEPROP 2 LAST CDS_LIB pure_quanta
J 0
(725 150);
DISPLAY INVISIBLE (725 150);
FORCEPROP 1 LAST PART_NUMBER CS29312FB02
J 0
(775 75);
DISPLAY 0.510638 (775 75);
DISPLAY INVISIBLE (775 75);
FORCEPROP 1 LAST PATH I63
J 0
(775 325);
DISPLAY 0.978723 (775 325);
PAINT WHITE (775 325);
DISPLAY INVISIBLE (775 325);
FORCEADD Q_CAP..1
(200 950);
FORCEPROP 1 LAST LOCATION PC2209
J 0
(250 975);
DISPLAY 0.638298 (250 975);
FORCEPROP 0 LAST $SEC 1
J 0
(250 1025);
DISPLAY 0.680851 (250 1025);
PAINT MONO (250 1025);
DISPLAY INVISIBLE (250 1025);
FORCEPROP 0 LAST CDS_SEC 1
J 0
(250 1025);
DISPLAY 1.021277 (250 1025);
DISPLAY INVISIBLE (250 1025);
FORCEPROP 1 LASTPIN (200 1050) $PN 1
J 0
(210 1030);
DISPLAY 0.787234 (210 1030);
PAINT MONO (210 1030);
FORCEPROP 1 LASTPIN (200 850) $PN 2
J 0
(210 830);
DISPLAY 0.787234 (210 830);
PAINT MONO (210 830);
FORCEPROP 1 LAST PACK_TYPE C0402
J 0
(250 875);
DISPLAY 0.510638 (250 875);
FORCEPROP 1 LAST VOLTAGE 25V
J 0
(250 900);
DISPLAY 0.510638 (250 900);
FORCEPROP 1 LAST MATERIAL X6S
J 0
(250 925);
DISPLAY 0.510638 (250 925);
FORCEPROP 1 LAST VALUE 1UF
J 0
(250 950);
DISPLAY 0.510638 (250 950);
FORCEPROP 0 LAST ROOM E1S_P12V_MAM_TIC_BOM1
J 0
(250 1025);
DISPLAY 0.446809 (250 1025);
PAINT RED (250 1025);
FORCEPROP 2 LAST CDS_LIB pure_quanta
J 0
(200 950);
DISPLAY INVISIBLE (200 950);
FORCEPROP 1 LAST TOLERANCE 10%
J 0
(250 900);
DISPLAY 0.638298 (250 900);
DISPLAY INVISIBLE (250 900);
FORCEPROP 1 LAST PART_NUMBER CH5104KEB02
J 0
(250 850);
DISPLAY 0.510638 (250 850);
DISPLAY INVISIBLE (250 850);
FORCEPROP 1 LAST PATH I64
J 0
(250 1100);
DISPLAY 0.978723 (250 1100);
PAINT WHITE (250 1100);
DISPLAY INVISIBLE (250 1100);
FORCEADD Q_RES..2
(200 1375);
FORCEPROP 1 LAST LOCATION PR3966
J 0
(250 1450);
DISPLAY 0.638298 (250 1450);
FORCEPROP 0 LAST $SEC 1
J 0
(250 1500);
DISPLAY 0.680851 (250 1500);
PAINT MONO (250 1500);
DISPLAY INVISIBLE (250 1500);
FORCEPROP 0 LAST CDS_SEC 1
J 0
(250 1500);
DISPLAY 1.021277 (250 1500);
DISPLAY INVISIBLE (250 1500);
FORCEPROP 1 LASTPIN (200 1475) $PN 1
J 0
(205 1437);
DISPLAY 0.787234 (205 1437);
PAINT MONO (205 1437);
FORCEPROP 1 LASTPIN (200 1275) $PN 2
J 0
(205 1285);
DISPLAY 0.787234 (205 1285);
PAINT MONO (205 1285);
FORCEPROP 1 LAST PACK_TYPE 0402LF
J 0
(250 1300);
DISPLAY 0.404255 (250 1300);
FORCEPROP 1 LAST WATTAGE 1/16W
J 0
(250 1375);
DISPLAY 0.404255 (250 1375);
FORCEPROP 0 LAST ROOM E1S_P12V_MAM_TIC_BOM1
J 0
(250 1500);
DISPLAY 0.446809 (250 1500);
PAINT RED (250 1500);
FORCEPROP 1 LAST TOLERANCE 1%
J 0
(250 1400);
DISPLAY 0.404255 (250 1400);
FORCEPROP 1 LAST VALUE 10
J 0
(250 1425);
DISPLAY 0.404255 (250 1425);
FORCEPROP 1 LAST MATERIAL CHIP
J 0
(250 1350);
DISPLAY 0.404255 (250 1350);
FORCEPROP 2 LAST CDS_LIB pure_quanta
J 0
(200 1375);
DISPLAY INVISIBLE (200 1375);
FORCEPROP 1 LAST PART_NUMBER CS01002FB07
J 0
(250 1325);
DISPLAY 0.404255 (250 1325);
DISPLAY INVISIBLE (250 1325);
FORCEPROP 1 LAST PATH I65
J 0
(250 1550);
DISPLAY 0.978723 (250 1550);
PAINT WHITE (250 1550);
DISPLAY INVISIBLE (250 1550);
FORCEADD MAX15090BEWIT..1
(1475 650);
FORCEPROP 1 LAST LOCATION PU294
J 0
(1222 1378);
DISPLAY 0.723404 (1222 1378);
PAINT GREEN (1222 1378);
FORCEPROP 0 LAST $SEC 1
J 0
(1225 1525);
DISPLAY 0.680851 (1225 1525);
PAINT MONO (1225 1525);
DISPLAY INVISIBLE (1225 1525);
FORCEPROP 0 LAST CDS_SEC 1
J 0
(1225 1525);
DISPLAY 1.021277 (1225 1525);
DISPLAY INVISIBLE (1225 1525);
FORCEPROP 0 LASTPIN (1075 350) $PN B1
J 2
(1065 360);
DISPLAY 0.680851 (1065 360);
PAINT MONO (1065 360);
FORCEPROP 0 LASTPIN (1875 350) $PN A7
J 0
(1885 360);
DISPLAY 0.680851 (1885 360);
PAINT MONO (1885 360);
FORCEPROP 0 LASTPIN (1075 250) $PN B7
J 2
(1065 260);
DISPLAY 0.680851 (1065 260);
PAINT MONO (1065 260);
FORCEPROP 0 LASTPIN (1875 550) $PN C7
J 0
(1885 560);
DISPLAY 0.680851 (1885 560);
PAINT MONO (1885 560);
FORCEPROP 0 LASTPIN (1875 750) $PN A6
J 0
(1885 760);
DISPLAY 0.680851 (1885 760);
PAINT MONO (1885 760);
FORCEPROP 0 LASTPIN (1875 250) $PN B2
J 0
(1885 260);
DISPLAY 0.680851 (1885 260);
PAINT MONO (1885 260);
FORCEPROP 0 LASTPIN (1875 200) $PN C1
J 0
(1885 210);
DISPLAY 0.680851 (1885 210);
PAINT MONO (1885 210);
FORCEPROP 0 LASTPIN (1875 150) $PN C2
J 0
(1885 160);
DISPLAY 0.680851 (1885 160);
PAINT MONO (1885 160);
FORCEPROP 0 LASTPIN (1075 1150) $PN A3
J 2
(1065 1160);
DISPLAY 0.680851 (1065 1160);
PAINT MONO (1065 1160);
FORCEPROP 0 LASTPIN (1075 1100) $PN A5
J 2
(1065 1110);
DISPLAY 0.680851 (1065 1110);
PAINT MONO (1065 1110);
FORCEPROP 0 LASTPIN (1075 1050) $PN B3
J 2
(1065 1060);
DISPLAY 0.680851 (1065 1060);
PAINT MONO (1065 1060);
FORCEPROP 0 LASTPIN (1075 1000) $PN B5
J 2
(1065 1010);
DISPLAY 0.680851 (1065 1010);
PAINT MONO (1065 1010);
FORCEPROP 0 LASTPIN (1075 950) $PN C3
J 2
(1065 960);
DISPLAY 0.680851 (1065 960);
PAINT MONO (1065 960);
FORCEPROP 0 LASTPIN (1075 900) $PN C5
J 2
(1065 910);
DISPLAY 0.680851 (1065 910);
PAINT MONO (1065 910);
FORCEPROP 0 LASTPIN (1075 850) $PN D5
J 2
(1065 860);
DISPLAY 0.680851 (1065 860);
PAINT MONO (1065 860);
FORCEPROP 0 LASTPIN (1875 450) $PN A1
J 0
(1885 460);
DISPLAY 0.680851 (1885 460);
PAINT MONO (1885 460);
FORCEPROP 0 LASTPIN (1875 1150) $PN A4
J 0
(1885 1160);
DISPLAY 0.680851 (1885 1160);
PAINT MONO (1885 1160);
FORCEPROP 0 LASTPIN (1875 1100) $PN B4
J 0
(1885 1110);
DISPLAY 0.680851 (1885 1110);
PAINT MONO (1885 1110);
FORCEPROP 0 LASTPIN (1875 1050) $PN B6
J 0
(1885 1060);
DISPLAY 0.680851 (1885 1060);
PAINT MONO (1885 1060);
FORCEPROP 0 LASTPIN (1875 1000) $PN C4
J 0
(1885 1010);
DISPLAY 0.680851 (1885 1010);
PAINT MONO (1885 1010);
FORCEPROP 0 LASTPIN (1875 950) $PN C6
J 0
(1885 960);
DISPLAY 0.680851 (1885 960);
PAINT MONO (1885 960);
FORCEPROP 0 LASTPIN (1875 900) $PN D4
J 0
(1885 910);
DISPLAY 0.680851 (1885 910);
PAINT MONO (1885 910);
FORCEPROP 0 LASTPIN (1875 850) $PN D6
J 0
(1885 860);
DISPLAY 0.680851 (1885 860);
PAINT MONO (1885 860);
FORCEPROP 0 LASTPIN (1075 450) $PN D3
J 2
(1065 460);
DISPLAY 0.680851 (1065 460);
PAINT MONO (1065 460);
FORCEPROP 0 LASTPIN (1875 650) $PN D7
J 0
(1885 660);
DISPLAY 0.680851 (1885 660);
PAINT MONO (1885 660);
FORCEPROP 0 LASTPIN (1075 650) $PN D1
J 2
(1065 660);
DISPLAY 0.680851 (1065 660);
PAINT MONO (1065 660);
FORCEPROP 0 LASTPIN (1075 550) $PN D2
J 2
(1065 560);
DISPLAY 0.680851 (1065 560);
PAINT MONO (1065 560);
FORCEPROP 0 LASTPIN (1075 750) $PN A2
J 2
(1065 760);
DISPLAY 0.680851 (1065 760);
PAINT MONO (1065 760);
FORCEPROP 0 LAST ROOM E1S_P12V_MAM_TIC_BOM1
J 0
(1225 1575);
DISPLAY 0.680851 (1225 1575);
PAINT RED (1225 1575);
FORCEPROP 1 LAST MATERIAL IC
J 0
(1222 1205);
DISPLAY 0.723404 (1222 1205);
PAINT GREEN (1222 1205);
FORCEPROP 2 LAST PART_TYPE SMLF
J 0
(1225 1475);
DISPLAY 1.021277 (1225 1475);
FORCEPROP 2 LAST VALUE MAX15090BEWI+T
J 0
(1225 1425);
DISPLAY 1.021277 (1225 1425);
FORCEPROP 1 LAST CDS_LMAN_SYM_OUTLINE -250,550,250,-550
J 0
(1475 650);
DISPLAY 0.468085 (1475 650);
PAINT GREEN (1475 650);
DISPLAY INVISIBLE (1475 650);
FORCEPROP 2 LAST CDS_LIB pure_quanta
J 0
(1475 650);
DISPLAY INVISIBLE (1475 650);
FORCEPROP 1 LAST PIN_NAMES_ROTATE TRUE
J 0
(1475 650);
DISPLAY 0.489362 (1475 650);
PAINT GREEN (1475 650);
DISPLAY INVISIBLE (1475 650);
FORCEPROP 1 LAST PART_NUMBER AL015080B00
J 0
(1222 1294);
DISPLAY 0.723404 (1222 1294);
PAINT GREEN (1222 1294);
DISPLAY INVISIBLE (1222 1294);
FORCEPROP 1 LAST PATH I66
J 0
(1725 100);
DISPLAY 0.723404 (1725 100);
PAINT GREEN (1725 100);
DISPLAY INVISIBLE (1725 100);
FORCEADD GND..1
(2200 -25);
FORCEPROP 3 LASTPIN (2200 25) SIG_NAME GND\g
J 0
(2210 35);
DISPLAY 0.659574 (2210 35);
PAINT MONO (2210 35);
DISPLAY INVISIBLE (2210 35);
FORCEPROP 1 LAST SIZE 1B
J 0
(2275 -75);
DISPLAY 0.872340 (2275 -75);
PAINT GREEN (2275 -75);
DISPLAY INVISIBLE (2275 -75);
FORCEPROP 2 LAST CDS_LIB pure_quanta_power
J 0
(2200 -25);
DISPLAY INVISIBLE (2200 -25);
FORCEPROP 1 LAST HDL_POWER GND
J 0
(2200 125);
DISPLAY 0.872340 (2200 125);
PAINT GREEN (2200 125);
DISPLAY INVISIBLE (2200 125);
FORCEPROP 1 LAST PATH I67
J 0
(2275 -25);
DISPLAY 0.872340 (2275 -25);
PAINT AQUA (2275 -25);
DISPLAY INVISIBLE (2275 -25);
FORCEADD Q_RES..2
(2325 275);
FORCEPROP 1 LAST LOCATION PR3970
J 0
(2375 325);
DISPLAY 0.638298 (2375 325);
FORCEPROP 0 LAST $SEC 1
J 0
(2375 450);
DISPLAY 0.680851 (2375 450);
PAINT MONO (2375 450);
DISPLAY INVISIBLE (2375 450);
FORCEPROP 0 LAST CDS_SEC 1
J 0
(2375 450);
DISPLAY 1.021277 (2375 450);
DISPLAY INVISIBLE (2375 450);
FORCEPROP 1 LASTPIN (2325 375) $PN 1
J 0
(2330 337);
DISPLAY 0.787234 (2330 337);
PAINT MONO (2330 337);
FORCEPROP 1 LASTPIN (2325 175) $PN 2
J 0
(2330 185);
DISPLAY 0.787234 (2330 185);
PAINT MONO (2330 185);
FORCEPROP 1 LAST MATERIAL CHIP
J 0
(2375 225);
DISPLAY 0.404255 (2375 225);
FORCEPROP 1 LAST PACK_TYPE 0402LF
J 0
(2375 175);
DISPLAY 0.404255 (2375 175);
FORCEPROP 0 LAST ROOM E1S_P12V_MAM_TIC_BOM1
J 0
(2275 150);
DISPLAY 0.361702 (2275 150);
PAINT RED (2275 150);
FORCEPROP 1 LAST WATTAGE 1/16W
J 0
(2375 250);
DISPLAY 0.404255 (2375 250);
FORCEPROP 1 LAST VALUE 2.67K
J 0
(2375 300);
DISPLAY 0.404255 (2375 300);
FORCEPROP 1 LAST TOLERANCE 1%
J 0
(2375 275);
DISPLAY 0.404255 (2375 275);
FORCEPROP 2 LAST CDS_LIB pure_quanta
J 0
(2325 275);
DISPLAY INVISIBLE (2325 275);
FORCEPROP 1 LAST PART_NUMBER CS22672FB03
J 0
(2375 200);
DISPLAY 0.404255 (2375 200);
DISPLAY INVISIBLE (2375 200);
FORCEPROP 1 LAST PATH I68
J 0
(2375 450);
DISPLAY 0.978723 (2375 450);
PAINT WHITE (2375 450);
DISPLAY INVISIBLE (2375 450);
FORCEADD Q_CAP..1
R 1
(2825 750);
FORCEPROP 1 LAST LOCATION PC2215
J 0
(2575 750);
DISPLAY 0.510638 (2575 750);
FORCEPROP 0 LAST $SEC 1
R 1
J 0
(2925 875);
DISPLAY 0.680851 (2925 875);
PAINT MONO (2925 875);
DISPLAY INVISIBLE (2925 875);
FORCEPROP 0 LAST CDS_SEC 1
R 1
J 0
(2925 875);
DISPLAY 1.021277 (2925 875);
DISPLAY INVISIBLE (2925 875);
FORCEPROP 1 LASTPIN (2725 750) $PN 1
R 1
J 0
(2745 760);
DISPLAY 0.787234 (2745 760);
PAINT MONO (2745 760);
FORCEPROP 1 LASTPIN (2925 750) $PN 2
R 1
J 0
(2945 760);
DISPLAY 0.787234 (2945 760);
PAINT MONO (2945 760);
FORCEPROP 1 LAST PACK_TYPE C0402
J 0
(2600 700);
DISPLAY 0.638298 (2600 700);
FORCEPROP 0 LAST ROOM E1S_P12V_MAM_TIC_BOM1
J 0
(2700 875);
DISPLAY 0.446809 (2700 875);
PAINT RED (2700 875);
FORCEPROP 1 LAST VOLTAGE 50V
J 0
(2950 825);
DISPLAY 0.510638 (2950 825);
FORCEPROP 1 LAST VALUE 3900PF
J 0
(2750 800);
DISPLAY 0.510638 (2750 800);
FORCEPROP 1 LAST TOLERANCE 10%
R 1
J 0
(2875 800);
DISPLAY 0.638298 (2875 800);
DISPLAY INVISIBLE (2875 800);
FORCEPROP 1 LAST MATERIAL X7R
R 1
J 0
(2825 800);
DISPLAY 0.638298 (2825 800);
DISPLAY INVISIBLE (2825 800);
FORCEPROP 2 LAST CDS_LIB pure_quanta
R 1
J 0
(2825 750);
DISPLAY INVISIBLE (2825 750);
FORCEPROP 1 LAST PART_NUMBER CH23906KB14
J 0
(2975 775);
DISPLAY 0.510638 (2975 775);
DISPLAY INVISIBLE (2975 775);
FORCEPROP 1 LAST PATH I69
R 1
J 0
(2675 800);
DISPLAY 0.978723 (2675 800);
PAINT WHITE (2675 800);
DISPLAY INVISIBLE (2675 800);
FORCEADD MOSFET_NCH_DUAL..2
(-2100 -2275);
FORCEPROP 1 LAST LOCATION Q126
J 0
(-1949 -2299);
DISPLAY 0.723404 (-1949 -2299);
PAINT GREEN (-1949 -2299);
FORCEPROP 0 LAST $SEC 2
J 0
(-1925 -2150);
DISPLAY 0.680851 (-1925 -2150);
PAINT MONO (-1925 -2150);
DISPLAY INVISIBLE (-1925 -2150);
FORCEPROP 0 LAST CDS_SEC 2
J 0
(-1925 -2150);
DISPLAY 1.021277 (-1925 -2150);
DISPLAY INVISIBLE (-1925 -2150);
FORCEPROP 0 LASTPIN (-2050 -2075) $PN 3
R 1
J 0
(-2060 -2065);
DISPLAY 0.680851 (-2060 -2065);
PAINT MONO (-2060 -2065);
FORCEPROP 0 LASTPIN (-2300 -2325) $PN 5
J 2
(-2310 -2315);
DISPLAY 0.680851 (-2310 -2315);
PAINT MONO (-2310 -2315);
FORCEPROP 0 LASTPIN (-2050 -2475) $PN 4
R 1
J 2
(-2060 -2485);
DISPLAY 0.680851 (-2060 -2485);
PAINT MONO (-2060 -2485);
FORCEPROP 1 LAST MATERIAL IC
J 0
(-1949 -2424);
DISPLAY 0.723404 (-1949 -2424);
PAINT GREEN (-1949 -2424);
FORCEPROP 0 LAST ROOM E1S_P3V3_BOM1
J 0
(-1925 -2100);
DISPLAY 0.680851 (-1925 -2100);
PAINT RED (-1925 -2100);
FORCEPROP 2 LAST VALUE PJT138K
J 0
(-1925 -2250);
DISPLAY 1.021277 (-1925 -2250);
FORCEPROP 2 LAST PART_TYPE SMLF
J 0
(-1925 -2200);
DISPLAY 1.021277 (-1925 -2200);
FORCEPROP 2 LAST CDS_LIB pure_quanta
J 0
(-2100 -2275);
DISPLAY INVISIBLE (-2100 -2275);
FORCEPROP 1 LAST CDS_LMAN_SYM_OUTLINE -150,150,150,-150
J 0
(-2100 -2275);
DISPLAY 0.468085 (-2100 -2275);
PAINT GREEN (-2100 -2275);
DISPLAY INVISIBLE (-2100 -2275);
FORCEPROP 1 LAST NEEDS_NO_SIZE TRUE
J 0
(-1950 -2384);
DISPLAY 0.468085 (-1950 -2384);
PAINT GREEN (-1950 -2384);
DISPLAY INVISIBLE (-1950 -2384);
FORCEPROP 1 LAST PART_NUMBER BAM138K0003
J 0
(-1949 -2369);
DISPLAY 0.723404 (-1949 -2369);
PAINT GREEN (-1949 -2369);
DISPLAY INVISIBLE (-1949 -2369);
FORCEPROP 1 LAST PATH I7
J 0
(-1950 -2425);
DISPLAY 0.723404 (-1950 -2425);
PAINT GREEN (-1950 -2425);
DISPLAY INVISIBLE (-1950 -2425);
FORCEADD Q_RES..1
(3100 450);
FORCEPROP 1 LAST LOCATION R3974
J 0
(3050 500);
DISPLAY 0.978723 (3050 500);
FORCEPROP 0 LAST $SEC 1
J 0
(3050 550);
DISPLAY 0.680851 (3050 550);
PAINT MONO (3050 550);
DISPLAY INVISIBLE (3050 550);
FORCEPROP 0 LAST CDS_SEC 1
J 0
(3050 550);
DISPLAY 1.021277 (3050 550);
DISPLAY INVISIBLE (3050 550);
FORCEPROP 1 LASTPIN (3000 450) $PN 1
J 0
(3012 462);
DISPLAY 0.787234 (3012 462);
PAINT MONO (3012 462);
FORCEPROP 1 LASTPIN (3200 450) $PN 2
J 0
(3162 462);
DISPLAY 0.787234 (3162 462);
PAINT MONO (3162 462);
FORCEPROP 1 LAST WATTAGE 1/16W
J 2
(2900 400);
DISPLAY 0.595745 (2900 400);
FORCEPROP 1 LAST PACK_TYPE 0402LF
J 0
(3250 400);
DISPLAY 0.595745 (3250 400);
FORCEPROP 1 LAST TOLERANCE 5%
J 0
(3275 450);
DISPLAY 0.595745 (3275 450);
FORCEPROP 1 LAST VALUE 0
J 2
(3250 450);
DISPLAY 0.595745 (3250 450);
FORCEPROP 1 LAST MATERIAL EMPTY
J 0
(2875 450);
DISPLAY 0.595745 (2875 450);
PAINT RED (2875 450);
FORCEPROP 2 LAST CDS_LIB pure_quanta
J 0
(3100 450);
DISPLAY INVISIBLE (3100 450);
FORCEPROP 1 LAST PART_NUMBER CS00002JB13
J 0
(2925 400);
DISPLAY 0.595745 (2925 400);
DISPLAY INVISIBLE (2925 400);
FORCEPROP 1 LAST PATH I70
J 0
(3050 600);
DISPLAY 0.978723 (3050 600);
PAINT WHITE (3050 600);
DISPLAY INVISIBLE (3050 600);
FORCEADD Q_RES..1
(2950 650);
FORCEPROP 1 LAST LOCATION R3972
J 0
(2600 650);
DISPLAY 0.638298 (2600 650);
FORCEPROP 0 LAST $SEC 1
J 0
(2900 725);
DISPLAY 0.680851 (2900 725);
PAINT MONO (2900 725);
DISPLAY INVISIBLE (2900 725);
FORCEPROP 0 LAST CDS_SEC 1
J 0
(2900 725);
DISPLAY 1.021277 (2900 725);
DISPLAY INVISIBLE (2900 725);
FORCEPROP 1 LASTPIN (2850 650) $PN 1
J 0
(2862 662);
DISPLAY 0.787234 (2862 662);
PAINT MONO (2862 662);
FORCEPROP 1 LASTPIN (3050 650) $PN 2
J 0
(3012 662);
DISPLAY 0.787234 (3012 662);
PAINT MONO (3012 662);
FORCEPROP 1 LAST TOLERANCE 5%
J 0
(3125 650);
DISPLAY 0.595745 (3125 650);
FORCEPROP 1 LAST VALUE 0
J 2
(3100 650);
DISPLAY 0.595745 (3100 650);
FORCEPROP 0 LAST ROOM E1S_P12V_MAM_TIC_BOM1
J 0
(2675 575);
DISPLAY 0.446809 (2675 575);
PAINT RED (2675 575);
FORCEPROP 1 LAST WATTAGE 1/16W
J 2
(2750 600);
DISPLAY 0.468085 (2750 600);
FORCEPROP 1 LAST PACK_TYPE 0402LF
J 0
(3075 600);
DISPLAY 0.468085 (3075 600);
FORCEPROP 1 LAST MATERIAL CHIP
J 0
(2725 650);
DISPLAY 0.595745 (2725 650);
FORCEPROP 2 LAST CDS_LIB pure_quanta
J 0
(2950 650);
DISPLAY INVISIBLE (2950 650);
FORCEPROP 1 LAST PART_NUMBER CS00002JB13
J 0
(2800 600);
DISPLAY 0.468085 (2800 600);
DISPLAY INVISIBLE (2800 600);
FORCEPROP 1 LAST PATH I71
J 0
(2900 800);
DISPLAY 0.978723 (2900 800);
PAINT WHITE (2900 800);
DISPLAY INVISIBLE (2900 800);
FORCEADD Q_CAP..1
(2275 975);
FORCEPROP 1 LAST LOCATION PC2214
J 0
(2325 1025);
DISPLAY 0.808511 (2325 1025);
FORCEPROP 0 LAST $SEC 1
J 0
(2325 1125);
DISPLAY 0.680851 (2325 1125);
PAINT MONO (2325 1125);
DISPLAY INVISIBLE (2325 1125);
FORCEPROP 0 LAST CDS_SEC 1
J 0
(2325 1125);
DISPLAY 1.021277 (2325 1125);
DISPLAY INVISIBLE (2325 1125);
FORCEPROP 1 LASTPIN (2275 1075) $PN 1
J 0
(2285 1055);
DISPLAY 0.787234 (2285 1055);
PAINT MONO (2285 1055);
FORCEPROP 1 LASTPIN (2275 875) $PN 2
J 0
(2285 855);
DISPLAY 0.787234 (2285 855);
PAINT MONO (2285 855);
FORCEPROP 1 LAST MATERIAL EMPTY
J 0
(2325 950);
DISPLAY 0.510638 (2325 950);
PAINT RED (2325 950);
FORCEPROP 1 LAST PACK_TYPE C0402
J 0
(2325 900);
DISPLAY 0.510638 (2325 900);
FORCEPROP 0 LAST ROOM E1S_P12V_MAM_TIC_BOM1
J 0
(2225 825);
DISPLAY 0.361702 (2225 825);
PAINT RED (2225 825);
FORCEPROP 1 LAST VOLTAGE 50V
J 0
(2325 975);
DISPLAY 0.510638 (2325 975);
FORCEPROP 1 LAST VALUE 0.01UF
J 0
(2325 1000);
DISPLAY 0.510638 (2325 1000);
FORCEPROP 1 LAST TOLERANCE 10%
J 0
(2325 925);
DISPLAY 0.638298 (2325 925);
DISPLAY INVISIBLE (2325 925);
FORCEPROP 2 LAST CDS_LIB pure_quanta
J 0
(2275 975);
DISPLAY INVISIBLE (2275 975);
FORCEPROP 1 LAST PART_NUMBER CH31006KB18
J 0
(2325 925);
DISPLAY 0.510638 (2325 925);
DISPLAY INVISIBLE (2325 925);
FORCEPROP 1 LAST PATH I72
J 0
(2325 1125);
DISPLAY 0.978723 (2325 1125);
PAINT WHITE (2325 1125);
DISPLAY INVISIBLE (2325 1125);
FORCEADD Q_RES..2
(2600 1000);
FORCEPROP 1 LAST LOCATION PR4528
J 0
(2650 1150);
DISPLAY 0.978723 (2650 1150);
FORCEPROP 0 LAST $SEC 1
J 0
(2625 1175);
DISPLAY 0.680851 (2625 1175);
PAINT MONO (2625 1175);
DISPLAY INVISIBLE (2625 1175);
FORCEPROP 0 LAST CDS_SEC 1
J 0
(2625 1175);
DISPLAY 1.021277 (2625 1175);
DISPLAY INVISIBLE (2625 1175);
FORCEPROP 1 LASTPIN (2600 1100) $PN 1
J 0
(2605 1062);
DISPLAY 0.787234 (2605 1062);
PAINT MONO (2605 1062);
FORCEPROP 1 LASTPIN (2600 900) $PN 2
J 0
(2605 910);
DISPLAY 0.787234 (2605 910);
PAINT MONO (2605 910);
FORCEPROP 0 LAST ROOM E1S_P12V_MAM_TIC_BOM1
J 0
(2650 950);
DISPLAY 0.446809 (2650 950);
PAINT RED (2650 950);
FORCEPROP 1 LAST PACK_TYPE 0402LF
J 0
(2650 975);
DISPLAY 0.510638 (2650 975);
FORCEPROP 1 LAST MATERIAL CHIP
J 0
(2650 1050);
DISPLAY 0.510638 (2650 1050);
FORCEPROP 1 LAST TOLERANCE 1%
J 0
(2650 1100);
DISPLAY 0.510638 (2650 1100);
FORCEPROP 1 LAST WATTAGE 1/16W
J 0
(2650 1075);
DISPLAY 0.510638 (2650 1075);
FORCEPROP 1 LAST VALUE 10M
J 0
(2650 1125);
DISPLAY 0.510638 (2650 1125);
FORCEPROP 2 LAST CDS_LIB pure_quanta
J 0
(2600 1000);
DISPLAY INVISIBLE (2600 1000);
FORCEPROP 1 LAST PART_NUMBER CS61002FB02
J 0
(2650 1025);
DISPLAY 0.510638 (2650 1025);
DISPLAY INVISIBLE (2650 1025);
FORCEPROP 1 LAST PATH I73
J 0
(2650 1175);
DISPLAY 0.978723 (2650 1175);
PAINT WHITE (2650 1175);
DISPLAY INVISIBLE (2650 1175);
FORCEADD SCHOTTKY_AC..1
R 1
(2700 1600);
FORCEPROP 1 LAST LOCATION PD112
J 0
(2750 1625);
DISPLAY 0.723404 (2750 1625);
PAINT GREEN (2750 1625);
FORCEPROP 0 LAST $SEC 1
R 1
J 0
(2750 1675);
DISPLAY INVISIBLE (2750 1675);
FORCEPROP 0 LAST CDS_SEC 1
R 1
J 0
(2750 1675);
DISPLAY INVISIBLE (2750 1675);
FORCEPROP 0 LASTPIN (2700 1475) $PN A
R 1
J 2
(2690 1510);
DISPLAY 0.808511 (2690 1510);
FORCEPROP 0 LASTPIN (2700 1725) $PN C
R 1
J 0
(2690 1685);
DISPLAY 0.808511 (2690 1685);
FORCEPROP 1 LAST MATERIAL IC
J 0
(2750 1500);
DISPLAY 0.723404 (2750 1500);
PAINT GREEN (2750 1500);
FORCEPROP 2 LAST VALUE B340A-13-F
J 0
(2750 1575);
DISPLAY 0.638298 (2750 1575);
FORCEPROP 1 LAST NEEDS_NO_SIZE TRUE
R 1
J 0
(2750 1675);
DISPLAY 0.468085 (2750 1675);
PAINT GREEN (2750 1675);
DISPLAY INVISIBLE (2750 1675);
FORCEPROP 1 LAST CDS_LMAN_SYM_OUTLINE -75,50,75,-50
R 1
J 0
(2700 1600);
DISPLAY 0.468085 (2700 1600);
PAINT GREEN (2700 1600);
DISPLAY INVISIBLE (2700 1600);
FORCEPROP 2 LAST CDS_LIB pure_quanta
R 1
J 0
(2700 1600);
DISPLAY INVISIBLE (2700 1600);
FORCEPROP 0 LAST PART_TYPE SMLF
J 0
(2750 1775);
DISPLAY 1.021277 (2750 1775);
DISPLAY INVISIBLE (2750 1775);
FORCEPROP 1 LAST PART_NUMBER BC000340Z30
J 0
(2750 1525);
DISPLAY 0.595745 (2750 1525);
PAINT GREEN (2750 1525);
DISPLAY INVISIBLE (2750 1525);
FORCEPROP 1 LAST PATH I74
R 1
J 0
(2700 1600);
DISPLAY 0.723404 (2700 1600);
PAINT GREEN (2700 1600);
DISPLAY INVISIBLE (2700 1600);
FORCEADD GND..1
(3075 700);
FORCEPROP 3 LASTPIN (3075 750) SIG_NAME GND\g
J 0
(3085 760);
DISPLAY 0.659574 (3085 760);
PAINT MONO (3085 760);
DISPLAY INVISIBLE (3085 760);
FORCEPROP 2 LAST CDS_LIB pure_quanta_power
J 0
(3075 700);
DISPLAY INVISIBLE (3075 700);
FORCEPROP 1 LAST SIZE 1B
J 0
(3150 650);
DISPLAY 0.872340 (3150 650);
PAINT GREEN (3150 650);
DISPLAY INVISIBLE (3150 650);
FORCEPROP 1 LAST HDL_POWER GND
J 0
(3075 850);
DISPLAY 0.872340 (3075 850);
PAINT GREEN (3075 850);
DISPLAY INVISIBLE (3075 850);
FORCEPROP 1 LAST PATH I75
J 0
(3150 700);
DISPLAY 0.872340 (3150 700);
PAINT AQUA (3150 700);
DISPLAY INVISIBLE (3150 700);
FORCEADD Q_RES..2
(3300 900);
FORCEPROP 1 LAST LOCATION R3976
J 0
(3345 1025);
DISPLAY 0.638298 (3345 1025);
FORCEPROP 0 LAST $SEC 1
J 0
(3350 1075);
DISPLAY 0.680851 (3350 1075);
PAINT MONO (3350 1075);
DISPLAY INVISIBLE (3350 1075);
FORCEPROP 0 LAST CDS_SEC 1
J 0
(3350 1075);
DISPLAY 1.021277 (3350 1075);
DISPLAY INVISIBLE (3350 1075);
FORCEPROP 1 LASTPIN (3300 1000) $PN 1
J 0
(3305 962);
DISPLAY 0.787234 (3305 962);
PAINT MONO (3305 962);
FORCEPROP 1 LASTPIN (3300 800) $PN 2
J 0
(3305 810);
DISPLAY 0.787234 (3305 810);
PAINT MONO (3305 810);
FORCEPROP 1 LAST WATTAGE 1/16W
J 0
(3340 875);
DISPLAY 0.510638 (3340 875);
FORCEPROP 1 LAST TOLERANCE 1%
J 0
(3345 925);
DISPLAY 0.510638 (3345 925);
FORCEPROP 0 LAST ROOM E1S_P12V_MAM_TIC_BOM1
J 0
(3350 1075);
DISPLAY 0.361702 (3350 1075);
PAINT RED (3350 1075);
FORCEPROP 1 LAST MATERIAL CHIP
J 0
(3340 825);
DISPLAY 0.510638 (3340 825);
FORCEPROP 1 LAST PACK_TYPE 0402LF
J 0
(3340 725);
DISPLAY 0.510638 (3340 725);
FORCEPROP 1 LAST VALUE 100K
J 0
(3345 975);
DISPLAY 0.510638 (3345 975);
FORCEPROP 2 LAST CDS_LIB pure_quanta
J 0
(3300 900);
DISPLAY INVISIBLE (3300 900);
FORCEPROP 1 LAST PART_NUMBER CS41002FB09
J 0
(3340 775);
DISPLAY 0.510638 (3340 775);
DISPLAY INVISIBLE (3340 775);
FORCEPROP 1 LAST PATH I76
J 0
(3350 1075);
DISPLAY 0.978723 (3350 1075);
PAINT WHITE (3350 1075);
DISPLAY INVISIBLE (3350 1075);
FORCEADD VCCAUX15..1
(3500 1250);
FORCEPROP 3 LASTPIN (3500 1200) SIG_NAME P3V3_AUX\g
J 0
(3510 1210);
DISPLAY 0.659574 (3510 1210);
PAINT MONO (3510 1210);
DISPLAY INVISIBLE (3510 1210);
FORCEPROP 1 LAST HDL_POWER P3V3_AUX
J 1
(3500 1300);
DISPLAY 0.723404 (3500 1300);
PAINT GREEN (3500 1300);
FORCEPROP 2 LAST CDS_LIB pure_quanta_power
J 0
(3500 1250);
DISPLAY INVISIBLE (3500 1250);
FORCEPROP 1 LAST PATH I77
J 0
(3550 1275);
DISPLAY 0.872340 (3550 1275);
PAINT AQUA (3550 1275);
DISPLAY INVISIBLE (3550 1275);
FORCEADD Q_CAP..1
(3175 1575);
FORCEPROP 1 LAST LOCATION PC2217
J 0
(3225 1675);
DISPLAY 0.638298 (3225 1675);
FORCEPROP 0 LAST $SEC 1
J 0
(3225 1725);
DISPLAY 0.680851 (3225 1725);
PAINT MONO (3225 1725);
DISPLAY INVISIBLE (3225 1725);
FORCEPROP 0 LAST CDS_SEC 1
J 0
(3225 1725);
DISPLAY 1.021277 (3225 1725);
DISPLAY INVISIBLE (3225 1725);
FORCEPROP 1 LASTPIN (3175 1675) $PN 1
J 0
(3185 1655);
DISPLAY 0.787234 (3185 1655);
PAINT MONO (3185 1655);
FORCEPROP 1 LASTPIN (3175 1475) $PN 2
J 0
(3185 1455);
DISPLAY 0.787234 (3185 1455);
PAINT MONO (3185 1455);
FORCEPROP 1 LAST VOLTAGE 25V
J 0
(3225 1575);
DISPLAY 0.638298 (3225 1575);
FORCEPROP 1 LAST VALUE 0.1UF
J 0
(3225 1625);
DISPLAY 0.638298 (3225 1625);
FORCEPROP 1 LAST MATERIAL X7R
J 0
(3225 1525);
DISPLAY 0.638298 (3225 1525);
FORCEPROP 1 LAST PACK_TYPE 0402
J 0
(3225 1425);
DISPLAY 0.638298 (3225 1425);
FORCEPROP 2 LAST CDS_LIB pure_quanta
J 0
(3175 1575);
DISPLAY INVISIBLE (3175 1575);
FORCEPROP 1 LAST TOLERANCE 10%
J 0
(3225 1525);
DISPLAY 0.978723 (3225 1525);
DISPLAY INVISIBLE (3225 1525);
FORCEPROP 1 LAST PART_NUMBER CH4104K1B00
J 0
(3225 1475);
DISPLAY 0.638298 (3225 1475);
DISPLAY INVISIBLE (3225 1475);
FORCEPROP 1 LAST PATH I78
J 0
(3225 1725);
DISPLAY 0.978723 (3225 1725);
PAINT WHITE (3225 1725);
DISPLAY INVISIBLE (3225 1725);
FORCEADD Q_CAP..1
(3600 1575);
FORCEPROP 1 LAST LOCATION PC2219
J 0
(3650 1675);
DISPLAY 0.638298 (3650 1675);
FORCEPROP 0 LAST $SEC 1
J 0
(3650 1725);
DISPLAY INVISIBLE (3650 1725);
FORCEPROP 0 LAST CDS_SEC 1
J 0
(3650 1725);
DISPLAY INVISIBLE (3650 1725);
FORCEPROP 1 LASTPIN (3600 1675) $PN 1
J 0
(3610 1655);
DISPLAY 0.787234 (3610 1655);
PAINT MONO (3610 1655);
DISPLAY INVISIBLE (3610 1655);
FORCEPROP 1 LASTPIN (3600 1475) $PN 2
J 0
(3610 1455);
DISPLAY 0.787234 (3610 1455);
PAINT MONO (3610 1455);
DISPLAY INVISIBLE (3610 1455);
FORCEPROP 1 LAST PACK_TYPE C0805
J 0
(3650 1425);
DISPLAY 0.638298 (3650 1425);
FORCEPROP 1 LAST MATERIAL X6S
J 0
(3650 1525);
DISPLAY 0.638298 (3650 1525);
FORCEPROP 1 LAST VOLTAGE 16V
J 0
(3650 1575);
DISPLAY 0.638298 (3650 1575);
FORCEPROP 1 LAST VALUE 10UF
J 0
(3650 1625);
DISPLAY 0.638298 (3650 1625);
FORCEPROP 1 LAST TOLERANCE 10%
J 0
(3650 1525);
DISPLAY 0.978723 (3650 1525);
DISPLAY INVISIBLE (3650 1525);
FORCEPROP 2 LAST CDS_LIB pure_quanta
J 0
(3600 1575);
DISPLAY INVISIBLE (3600 1575);
FORCEPROP 1 LAST PART_NUMBER CH6103KEA01
J 0
(3650 1475);
DISPLAY 0.638298 (3650 1475);
DISPLAY INVISIBLE (3650 1475);
FORCEPROP 1 LAST PATH I79
J 0
(3650 1725);
DISPLAY 0.978723 (3650 1725);
PAINT WHITE (3650 1725);
DISPLAY INVISIBLE (3650 1725);
FORCEADD Q_RES..2
(-2725 -2000);
FORCEPROP 1 LAST LOCATION R4072
J 0
(-2690 -1833);
DISPLAY 0.638298 (-2690 -1833);
FORCEPROP 0 LAST $SEC 1
J 0
(-2675 -1800);
DISPLAY 0.680851 (-2675 -1800);
PAINT MONO (-2675 -1800);
DISPLAY INVISIBLE (-2675 -1800);
FORCEPROP 0 LAST CDS_SEC 1
J 0
(-2675 -1800);
DISPLAY 1.021277 (-2675 -1800);
DISPLAY INVISIBLE (-2675 -1800);
FORCEPROP 1 LASTPIN (-2725 -1900) $PN 1
J 0
(-2720 -1938);
DISPLAY 0.787234 (-2720 -1938);
PAINT MONO (-2720 -1938);
FORCEPROP 1 LASTPIN (-2725 -2100) $PN 2
J 0
(-2720 -2090);
DISPLAY 0.787234 (-2720 -2090);
PAINT MONO (-2720 -2090);
FORCEPROP 1 LAST VALUE 10K
J 0
(-2690 -1883);
DISPLAY 0.638298 (-2690 -1883);
FORCEPROP 1 LAST WATTAGE 1/16W
J 0
(-2695 -1983);
DISPLAY 0.638298 (-2695 -1983);
FORCEPROP 1 LAST TOLERANCE 1%
J 0
(-2690 -1933);
DISPLAY 0.638298 (-2690 -1933);
FORCEPROP 0 LAST ROOM E1S_P3V3_BOM1
J 0
(-2675 -1750);
DISPLAY 0.680851 (-2675 -1750);
PAINT RED (-2675 -1750);
FORCEPROP 1 LAST MATERIAL CHIP
J 0
(-2695 -2033);
DISPLAY 0.638298 (-2695 -2033);
FORCEPROP 1 LAST PACK_TYPE 0402LF
J 0
(-2695 -2133);
DISPLAY 0.638298 (-2695 -2133);
FORCEPROP 2 LAST CDS_LIB pure_quanta
J 0
(-2725 -2000);
DISPLAY INVISIBLE (-2725 -2000);
FORCEPROP 1 LAST PART_NUMBER CS31002FB08
J 0
(-2695 -2083);
DISPLAY 0.638298 (-2695 -2083);
DISPLAY INVISIBLE (-2695 -2083);
FORCEPROP 1 LAST PATH I8
J 0
(-2675 -1825);
DISPLAY 0.978723 (-2675 -1825);
PAINT WHITE (-2675 -1825);
DISPLAY INVISIBLE (-2675 -1825);
FORCEADD Q_CAP..1
(4000 1575);
FORCEPROP 1 LAST LOCATION PC2280
J 0
(4050 1675);
DISPLAY 0.680851 (4050 1675);
FORCEPROP 0 LAST $SEC 1
J 0
(4050 1725);
DISPLAY INVISIBLE (4050 1725);
FORCEPROP 0 LAST CDS_SEC 1
J 0
(4050 1725);
DISPLAY INVISIBLE (4050 1725);
FORCEPROP 1 LASTPIN (4000 1675) $PN 1
J 0
(4010 1655);
DISPLAY 0.787234 (4010 1655);
PAINT MONO (4010 1655);
DISPLAY INVISIBLE (4010 1655);
FORCEPROP 1 LASTPIN (4000 1475) $PN 2
J 0
(4010 1455);
DISPLAY 0.787234 (4010 1455);
PAINT MONO (4010 1455);
DISPLAY INVISIBLE (4010 1455);
FORCEPROP 1 LAST PACK_TYPE C0805
J 0
(4050 1425);
DISPLAY 0.638298 (4050 1425);
FORCEPROP 1 LAST VALUE 10UF
J 0
(4050 1625);
DISPLAY 0.638298 (4050 1625);
FORCEPROP 1 LAST VOLTAGE 16V
J 0
(4050 1575);
DISPLAY 0.638298 (4050 1575);
FORCEPROP 1 LAST MATERIAL X6S
J 0
(4050 1525);
DISPLAY 0.638298 (4050 1525);
FORCEPROP 2 LAST CDS_LIB pure_quanta
J 0
(4000 1575);
DISPLAY INVISIBLE (4000 1575);
FORCEPROP 1 LAST TOLERANCE 10%
J 0
(3789 1535);
DISPLAY 0.787234 (3789 1535);
PAINT GREEN (3789 1535);
DISPLAY INVISIBLE (3789 1535);
FORCEPROP 1 LAST PART_NUMBER CH6103KEA01
J 0
(4050 1475);
DISPLAY 0.638298 (4050 1475);
DISPLAY INVISIBLE (4050 1475);
FORCEPROP 1 LAST PATH I80
J 0
(4050 1725);
DISPLAY 0.978723 (4050 1725);
PAINT WHITE (4050 1725);
DISPLAY INVISIBLE (4050 1725);
FORCEADD UNIVERSAL_POWER..1
R 2
(4000 1875);
FORCEPROP 3 LASTPIN (4000 1825) SIG_NAME P12V_E1S_0\g
J 0
(4010 1835);
DISPLAY 0.659574 (4010 1835);
PAINT MONO (4010 1835);
DISPLAY INVISIBLE (4010 1835);
FORCEPROP 1 LAST HDL_POWER P12V_E1S_0
J 1
(4025 1925);
DISPLAY 0.723404 (4025 1925);
PAINT GREEN (4025 1925);
FORCEPROP 2 LAST CDS_LIB pure_quanta_power
J 0
(4000 1875);
DISPLAY INVISIBLE (4000 1875);
FORCEPROP 1 LAST PATH I81
J 2
(3950 1900);
DISPLAY 0.872340 (3950 1900);
PAINT AQUA (3950 1900);
DISPLAY INVISIBLE (3950 1900);
FORCEADD OFFPAGE..2
(4250 225);
PAINT AQUA (4250 225);
FORCEPROP 2 LAST $XR0 258 
J 0
(4439 225);
DISPLAY 0.638298 (4439 225);
PAINT MONO (4439 225);
FORCEPROP 2 LAST CDS_LIB standard
J 0
(4250 225);
DISPLAY INVISIBLE (4250 225);
FORCEPROP 1 LAST OFFPAGE TRUE
J 0
(4575 100);
DISPLAY 0.872340 (4575 100);
PAINT AQUA (4575 100);
DISPLAY INVISIBLE (4575 100);
FORCEPROP 1 LAST COMMENT_BODY TRUE
J 0
(4205 130);
DISPLAY 0.872340 (4205 130);
PAINT GREEN (4205 130);
DISPLAY INVISIBLE (4205 130);
FORCEPROP 2 LAST PATH I82
J 0
(4450 275);
DISPLAY 0.680851 (4450 275);
DISPLAY INVISIBLE (4450 275);
FORCEADD OFFPAGE..2
(4250 450);
PAINT AQUA (4250 450);
FORCEPROP 2 LAST $XR0 258 
J 0
(4439 450);
DISPLAY 0.638298 (4439 450);
PAINT MONO (4439 450);
FORCEPROP 2 LAST CDS_LIB standard
J 0
(4250 450);
DISPLAY INVISIBLE (4250 450);
FORCEPROP 1 LAST OFFPAGE TRUE
J 0
(4575 325);
DISPLAY 0.872340 (4575 325);
PAINT AQUA (4575 325);
DISPLAY INVISIBLE (4575 325);
FORCEPROP 1 LAST COMMENT_BODY TRUE
J 0
(4205 355);
DISPLAY 0.872340 (4205 355);
PAINT GREEN (4205 355);
DISPLAY INVISIBLE (4205 355);
FORCEPROP 2 LAST PATH I83
J 0
(4450 500);
DISPLAY 0.680851 (4450 500);
DISPLAY INVISIBLE (4450 500);
FORCEADD OFFPAGE..2
(4250 650);
PAINT AQUA (4250 650);
FORCEPROP 2 LAST $XR1 81 
J 0
(4559 650);
DISPLAY 0.638298 (4559 650);
PAINT MONO (4559 650);
FORCEPROP 2 LAST $XR0 147 
J 0
(4439 650);
DISPLAY 0.638298 (4439 650);
PAINT MONO (4439 650);
FORCEPROP 2 LAST CDS_LIB standard
J 0
(4250 650);
DISPLAY INVISIBLE (4250 650);
FORCEPROP 1 LAST OFFPAGE TRUE
J 0
(4575 525);
DISPLAY 0.872340 (4575 525);
PAINT AQUA (4575 525);
DISPLAY INVISIBLE (4575 525);
FORCEPROP 1 LAST COMMENT_BODY TRUE
J 0
(4205 555);
DISPLAY 0.872340 (4205 555);
PAINT GREEN (4205 555);
DISPLAY INVISIBLE (4205 555);
FORCEPROP 2 LAST PATH I84
J 0
(4450 700);
DISPLAY 0.680851 (4450 700);
DISPLAY INVISIBLE (4450 700);
FORCEADD GND..1
(4000 1275);
FORCEPROP 3 LASTPIN (4000 1325) SIG_NAME GND\g
J 0
(4010 1335);
DISPLAY 0.659574 (4010 1335);
PAINT MONO (4010 1335);
DISPLAY INVISIBLE (4010 1335);
FORCEPROP 1 LAST SIZE 1B
J 0
(4075 1225);
DISPLAY 0.872340 (4075 1225);
PAINT GREEN (4075 1225);
DISPLAY INVISIBLE (4075 1225);
FORCEPROP 2 LAST CDS_LIB pure_quanta_power
J 0
(4000 1275);
DISPLAY INVISIBLE (4000 1275);
FORCEPROP 1 LAST HDL_POWER GND
J 0
(4000 1425);
DISPLAY 0.872340 (4000 1425);
PAINT GREEN (4000 1425);
DISPLAY INVISIBLE (4000 1425);
FORCEPROP 1 LAST PATH I85
J 0
(4075 1275);
DISPLAY 0.872340 (4075 1275);
PAINT AQUA (4075 1275);
DISPLAY INVISIBLE (4075 1275);
FORCEADD Q_RES..2
(3725 900);
FORCEPROP 1 LAST LOCATION R3978
J 0
(3770 1025);
DISPLAY 0.638298 (3770 1025);
FORCEPROP 0 LAST $SEC 1
J 0
(3775 1075);
DISPLAY 0.680851 (3775 1075);
PAINT MONO (3775 1075);
DISPLAY INVISIBLE (3775 1075);
FORCEPROP 0 LAST CDS_SEC 1
J 0
(3775 1075);
DISPLAY 1.021277 (3775 1075);
DISPLAY INVISIBLE (3775 1075);
FORCEPROP 1 LASTPIN (3725 1000) $PN 1
J 0
(3730 962);
DISPLAY 0.787234 (3730 962);
PAINT MONO (3730 962);
FORCEPROP 1 LASTPIN (3725 800) $PN 2
J 0
(3730 810);
DISPLAY 0.787234 (3730 810);
PAINT MONO (3730 810);
FORCEPROP 1 LAST WATTAGE 1/16W
J 0
(3765 875);
DISPLAY 0.510638 (3765 875);
FORCEPROP 0 LAST ROOM E1S_P12V_MAM_TIC_BOM1
J 0
(3775 1075);
DISPLAY 0.446809 (3775 1075);
PAINT RED (3775 1075);
FORCEPROP 1 LAST PACK_TYPE 0402LF
J 0
(3765 725);
DISPLAY 0.510638 (3765 725);
FORCEPROP 1 LAST MATERIAL CHIP
J 0
(3765 825);
DISPLAY 0.510638 (3765 825);
FORCEPROP 1 LAST TOLERANCE 1%
J 0
(3770 925);
DISPLAY 0.510638 (3770 925);
FORCEPROP 1 LAST VALUE 100K
J 0
(3770 975);
DISPLAY 0.510638 (3770 975);
FORCEPROP 2 LAST CDS_LIB pure_quanta
J 0
(3725 900);
DISPLAY INVISIBLE (3725 900);
FORCEPROP 1 LAST PART_NUMBER CS41002FB09
J 0
(3765 775);
DISPLAY 0.510638 (3765 775);
DISPLAY INVISIBLE (3765 775);
FORCEPROP 1 LAST PATH I86
J 0
(3775 1075);
DISPLAY 0.978723 (3775 1075);
PAINT WHITE (3775 1075);
DISPLAY INVISIBLE (3775 1075);
FORCEADD Q_RES..1
(3100 225);
FORCEPROP 1 LAST LOCATION R3975
J 0
(3050 275);
DISPLAY 0.978723 (3050 275);
FORCEPROP 0 LAST $SEC 1
J 0
(3050 325);
DISPLAY 0.680851 (3050 325);
PAINT MONO (3050 325);
DISPLAY INVISIBLE (3050 325);
FORCEPROP 0 LAST CDS_SEC 1
J 0
(3050 325);
DISPLAY 1.021277 (3050 325);
DISPLAY INVISIBLE (3050 325);
FORCEPROP 1 LASTPIN (3000 225) $PN 1
J 0
(3012 237);
DISPLAY 0.787234 (3012 237);
PAINT MONO (3012 237);
FORCEPROP 1 LASTPIN (3200 225) $PN 2
J 0
(3162 237);
DISPLAY 0.787234 (3162 237);
PAINT MONO (3162 237);
FORCEPROP 1 LAST MATERIAL CHIP
J 0
(2875 225);
DISPLAY 0.595745 (2875 225);
FORCEPROP 0 LAST ROOM E1S_P12V_MAM_TIC_BOM1
J 0
(2850 150);
DISPLAY 0.553191 (2850 150);
PAINT RED (2850 150);
FORCEPROP 1 LAST WATTAGE 1/16W
J 2
(2900 175);
DISPLAY 0.595745 (2900 175);
FORCEPROP 1 LAST TOLERANCE 5%
J 0
(3275 225);
DISPLAY 0.595745 (3275 225);
FORCEPROP 1 LAST VALUE 0
J 2
(3250 225);
DISPLAY 0.595745 (3250 225);
FORCEPROP 1 LAST PACK_TYPE 0402LF
J 0
(3250 175);
DISPLAY 0.595745 (3250 175);
FORCEPROP 2 LAST CDS_LIB pure_quanta
J 0
(3100 225);
DISPLAY INVISIBLE (3100 225);
FORCEPROP 1 LAST PART_NUMBER CS00002JB13
J 0
(2925 175);
DISPLAY 0.595745 (2925 175);
DISPLAY INVISIBLE (2925 175);
FORCEPROP 1 LAST PATH I87
J 0
(3050 375);
DISPLAY 0.978723 (3050 375);
PAINT WHITE (3050 375);
DISPLAY INVISIBLE (3050 375);
FORCEADD MAX15090BEWIT..1
(1475 -2050);
FORCEPROP 1 LAST LOCATION PU295
J 0
(1222 -1322);
DISPLAY 0.723404 (1222 -1322);
PAINT GREEN (1222 -1322);
FORCEPROP 0 LAST $SEC 1
J 0
(1225 -1175);
DISPLAY 0.680851 (1225 -1175);
PAINT MONO (1225 -1175);
DISPLAY INVISIBLE (1225 -1175);
FORCEPROP 0 LAST CDS_SEC 1
J 0
(1225 -1175);
DISPLAY 1.021277 (1225 -1175);
DISPLAY INVISIBLE (1225 -1175);
FORCEPROP 0 LASTPIN (1075 -2350) $PN B1
J 2
(1065 -2340);
DISPLAY 0.680851 (1065 -2340);
PAINT MONO (1065 -2340);
FORCEPROP 0 LASTPIN (1875 -2350) $PN A7
J 0
(1885 -2340);
DISPLAY 0.680851 (1885 -2340);
PAINT MONO (1885 -2340);
FORCEPROP 0 LASTPIN (1075 -2450) $PN B7
J 2
(1065 -2440);
DISPLAY 0.680851 (1065 -2440);
PAINT MONO (1065 -2440);
FORCEPROP 0 LASTPIN (1875 -2150) $PN C7
J 0
(1885 -2140);
DISPLAY 0.680851 (1885 -2140);
PAINT MONO (1885 -2140);
FORCEPROP 0 LASTPIN (1875 -1950) $PN A6
J 0
(1885 -1940);
DISPLAY 0.680851 (1885 -1940);
PAINT MONO (1885 -1940);
FORCEPROP 0 LASTPIN (1875 -2450) $PN B2
J 0
(1885 -2440);
DISPLAY 0.680851 (1885 -2440);
PAINT MONO (1885 -2440);
FORCEPROP 0 LASTPIN (1875 -2500) $PN C1
J 0
(1885 -2490);
DISPLAY 0.680851 (1885 -2490);
PAINT MONO (1885 -2490);
FORCEPROP 0 LASTPIN (1875 -2550) $PN C2
J 0
(1885 -2540);
DISPLAY 0.680851 (1885 -2540);
PAINT MONO (1885 -2540);
FORCEPROP 0 LASTPIN (1075 -1550) $PN A3
J 2
(1065 -1540);
DISPLAY 0.680851 (1065 -1540);
PAINT MONO (1065 -1540);
FORCEPROP 0 LASTPIN (1075 -1600) $PN A5
J 2
(1065 -1590);
DISPLAY 0.680851 (1065 -1590);
PAINT MONO (1065 -1590);
FORCEPROP 0 LASTPIN (1075 -1650) $PN B3
J 2
(1065 -1640);
DISPLAY 0.680851 (1065 -1640);
PAINT MONO (1065 -1640);
FORCEPROP 0 LASTPIN (1075 -1700) $PN B5
J 2
(1065 -1690);
DISPLAY 0.680851 (1065 -1690);
PAINT MONO (1065 -1690);
FORCEPROP 0 LASTPIN (1075 -1750) $PN C3
J 2
(1065 -1740);
DISPLAY 0.680851 (1065 -1740);
PAINT MONO (1065 -1740);
FORCEPROP 0 LASTPIN (1075 -1800) $PN C5
J 2
(1065 -1790);
DISPLAY 0.680851 (1065 -1790);
PAINT MONO (1065 -1790);
FORCEPROP 0 LASTPIN (1075 -1850) $PN D5
J 2
(1065 -1840);
DISPLAY 0.680851 (1065 -1840);
PAINT MONO (1065 -1840);
FORCEPROP 0 LASTPIN (1875 -2250) $PN A1
J 0
(1885 -2240);
DISPLAY 0.680851 (1885 -2240);
PAINT MONO (1885 -2240);
FORCEPROP 0 LASTPIN (1875 -1550) $PN A4
J 0
(1885 -1540);
DISPLAY 0.680851 (1885 -1540);
PAINT MONO (1885 -1540);
FORCEPROP 0 LASTPIN (1875 -1600) $PN B4
J 0
(1885 -1590);
DISPLAY 0.680851 (1885 -1590);
PAINT MONO (1885 -1590);
FORCEPROP 0 LASTPIN (1875 -1650) $PN B6
J 0
(1885 -1640);
DISPLAY 0.680851 (1885 -1640);
PAINT MONO (1885 -1640);
FORCEPROP 0 LASTPIN (1875 -1700) $PN C4
J 0
(1885 -1690);
DISPLAY 0.680851 (1885 -1690);
PAINT MONO (1885 -1690);
FORCEPROP 0 LASTPIN (1875 -1750) $PN C6
J 0
(1885 -1740);
DISPLAY 0.680851 (1885 -1740);
PAINT MONO (1885 -1740);
FORCEPROP 0 LASTPIN (1875 -1800) $PN D4
J 0
(1885 -1790);
DISPLAY 0.680851 (1885 -1790);
PAINT MONO (1885 -1790);
FORCEPROP 0 LASTPIN (1875 -1850) $PN D6
J 0
(1885 -1840);
DISPLAY 0.680851 (1885 -1840);
PAINT MONO (1885 -1840);
FORCEPROP 0 LASTPIN (1075 -2250) $PN D3
J 2
(1065 -2240);
DISPLAY 0.680851 (1065 -2240);
PAINT MONO (1065 -2240);
FORCEPROP 0 LASTPIN (1875 -2050) $PN D7
J 0
(1885 -2040);
DISPLAY 0.680851 (1885 -2040);
PAINT MONO (1885 -2040);
FORCEPROP 0 LASTPIN (1075 -2050) $PN D1
J 2
(1065 -2040);
DISPLAY 0.680851 (1065 -2040);
PAINT MONO (1065 -2040);
FORCEPROP 0 LASTPIN (1075 -2150) $PN D2
J 2
(1065 -2140);
DISPLAY 0.680851 (1065 -2140);
PAINT MONO (1065 -2140);
FORCEPROP 0 LASTPIN (1075 -1950) $PN A2
J 2
(1065 -1940);
DISPLAY 0.680851 (1065 -1940);
PAINT MONO (1065 -1940);
FORCEPROP 2 LAST VALUE MAX15090BEWI+T
J 0
(1225 -1275);
DISPLAY 1.021277 (1225 -1275);
FORCEPROP 2 LAST PART_TYPE SMLF
J 0
(1225 -1225);
DISPLAY 1.021277 (1225 -1225);
FORCEPROP 0 LAST ROOM E1S_P3V3_BOM1
J 0
(1225 -1125);
DISPLAY 0.680851 (1225 -1125);
PAINT RED (1225 -1125);
FORCEPROP 1 LAST MATERIAL IC
J 0
(1222 -1495);
DISPLAY 0.723404 (1222 -1495);
PAINT GREEN (1222 -1495);
FORCEPROP 1 LAST CDS_LMAN_SYM_OUTLINE -250,550,250,-550
J 0
(1475 -2050);
DISPLAY 0.468085 (1475 -2050);
PAINT GREEN (1475 -2050);
DISPLAY INVISIBLE (1475 -2050);
FORCEPROP 2 LAST CDS_LIB pure_quanta
J 0
(1475 -2050);
DISPLAY INVISIBLE (1475 -2050);
FORCEPROP 1 LAST PIN_NAMES_ROTATE TRUE
J 0
(1475 -2050);
DISPLAY 0.489362 (1475 -2050);
PAINT GREEN (1475 -2050);
DISPLAY INVISIBLE (1475 -2050);
FORCEPROP 1 LAST PART_NUMBER AL015080B00
J 0
(1222 -1406);
DISPLAY 0.723404 (1222 -1406);
PAINT GREEN (1222 -1406);
DISPLAY INVISIBLE (1222 -1406);
FORCEPROP 1 LAST PATH I88
J 0
(1725 -2600);
DISPLAY 0.723404 (1725 -2600);
PAINT GREEN (1725 -2600);
DISPLAY INVISIBLE (1725 -2600);
FORCEADD UNIVERSAL_POWER..1
(-2725 -1750);
FORCEPROP 3 LASTPIN (-2725 -1800) SIG_NAME P12V_AUX\g
J 0
(-2715 -1790);
DISPLAY 0.659574 (-2715 -1790);
PAINT MONO (-2715 -1790);
DISPLAY INVISIBLE (-2715 -1790);
FORCEPROP 1 LAST HDL_POWER P12V_AUX
J 1
(-2725 -1700);
DISPLAY 0.872340 (-2725 -1700);
PAINT GREEN (-2725 -1700);
FORCEPROP 2 LAST CDS_LIB pure_quanta_power
J 0
(-2725 -1750);
DISPLAY INVISIBLE (-2725 -1750);
FORCEPROP 1 LAST PATH I9
J 0
(-2675 -1725);
DISPLAY 0.872340 (-2675 -1725);
PAINT AQUA (-2675 -1725);
DISPLAY INVISIBLE (-2675 -1725);
FORCEADD QUANTA_TITLE_BLOCK_C..1
(4675 -3375);
FORCEPROP 0 LAST CDS_CON_LAST_MODIFIED Thu Sep 14 16:12:27 2023
J 0
(2790 -3360);
PAINT MONO (2790 -3360);
DISPLAY INVISIBLE (2790 -3360);
FORCEPROP 2 LAST CUSTOM_TXT_CDS <XR_PAGE_TITLE>
J 0
(-3215 1875);
DISPLAY 0.638298 (-3215 1875);
PAINT PINK (-3215 1875);
DISPLAY INVISIBLE (-3215 1875);
FORCEPROP 2 LAST CUSTOM_TXT_CDS <CON_LAST_MODIFIED>
J 0
(2790 -3360);
DISPLAY 0.978723 (2790 -3360);
FORCEPROP 2 LAST CUSTOM_TXT_CDS <Q_PROJ>
J 0
(2293 -3273);
DISPLAY 1.212766 (2293 -3273);
FORCEPROP 2 LAST CUSTOM_TXT_CDS <NAME_1>
J 0
(1500 -3200);
FORCEPROP 2 LAST CUSTOM_TXT_CDS <NAME_2>
J 0
(1500 -3325);
FORCEPROP 2 LAST CUSTOM_TXT_CDS <Q_REV>
J 0
(4491 -3272);
DISPLAY 1.212766 (4491 -3272);
FORCEPROP 2 LAST CUSTOM_TXT_CDS <CON_PAGE_NUM> OF <CON_TOTAL_PAGES>
J 0
(4229 -3357);
DISPLAY 0.978723 (4229 -3357);
FORCEPROP 2 LAST CUSTOM_TXT_CDS <Q_NUMBER>
J 0
(3272 -3272);
DISPLAY 1.212766 (3272 -3272);
FORCEPROP 1 LAST Q_TITLE E1S_HSC
J 0
(-4591 -3324);
DISPLAY 2.446809 (-4591 -3324);
PAINT GREEN (-4591 -3324);
FORCEPROP 2 LAST PAGE_BORDER TRUE
J 0
(-3215 1875);
DISPLAY 0.638298 (-3215 1875);
PAINT PINK (-3215 1875);
DISPLAY INVISIBLE (-3215 1875);
FORCEPROP 2 LAST CDS_LIB pure_quanta
J 0
(4675 -3375);
PAINT MONO (4675 -3375);
DISPLAY INVISIBLE (4675 -3375);
FORCEPROP 1 LAST CDS_LMAN_SYM_OUTLINE -9475,6775,100,-125
J 0
(4675 -3375);
DISPLAY 0.468085 (4675 -3375);
PAINT GREEN (4675 -3375);
DISPLAY INVISIBLE (4675 -3375);
FORCEPROP 2 LAST CDS_XR_PAGE_TITLE CR-146 : @T6G_MB_LIB.T6G(SCH_1):PAGE146
J 0
(-3215 1875);
DISPLAY 0.638298 (-3215 1875);
PAINT PINK (-3215 1875);
DISPLAY INVISIBLE (-3215 1875);
FORCEPROP 1 LAST COMMENT_BODY TRUE
J 0
(4687 -3388);
DISPLAY 0.978723 (4687 -3388);
PAINT GREEN (4687 -3388);
DISPLAY INVISIBLE (4687 -3388);
FORCEPROP 1 LAST Q_DEPT CCBU
J 1
(912 -3326);
DISPLAY 1.957447 (912 -3326);
PAINT GREEN (912 -3326);
DISPLAY INVISIBLE (912 -3326);
FORCEADD DNS..2
(2300 975);
PAINT RED (2300 975);
FORCEPROP 2 LAST CDS_LIB mstr_misc
J 0
(2300 975);
DISPLAY INVISIBLE (2300 975);
FORCEPROP 1 LAST COMMENT_BODY TRUE
R 1
J 0
(2375 750);
DISPLAY 0.872340 (2375 750);
PAINT GREEN (2375 750);
DISPLAY INVISIBLE (2375 750);
FORCEADD CAD_NOTE..1
(2875 -75);
FORCEPROP 0 LAST S1 R3974/R3975 CO-LAYOUT
J 0
(2750 -200);
DISPLAY 0.808511 (2750 -200);
PAINT WHITE (2750 -200);
FORCEPROP 2 LAST CDS_LIB pure_quanta_power
J 0
(2875 -75);
DISPLAY INVISIBLE (2875 -75);
FORCEPROP 1 LAST COMMENT_BODY TRUE
J 0
(2900 25);
DISPLAY 0.978723 (2900 25);
DISPLAY INVISIBLE (2900 25);
FORCEADD DNS..2
(3125 450);
PAINT RED (3125 450);
FORCEPROP 2 LAST CDS_LIB mstr_misc
J 0
(3125 450);
DISPLAY INVISIBLE (3125 450);
FORCEPROP 1 LAST COMMENT_BODY TRUE
R 1
J 0
(3200 225);
DISPLAY 0.872340 (3200 225);
PAINT GREEN (3200 225);
DISPLAY INVISIBLE (3200 225);
FORCEADD DNS..2
(2300 -1725);
PAINT RED (2300 -1725);
FORCEPROP 2 LAST CDS_LIB mstr_misc
J 0
(2300 -1725);
DISPLAY INVISIBLE (2300 -1725);
FORCEPROP 1 LAST COMMENT_BODY TRUE
R 1
J 0
(2375 -1950);
DISPLAY 0.872340 (2375 -1950);
PAINT GREEN (2375 -1950);
DISPLAY INVISIBLE (2375 -1950);
WIRE 16 -1 (-3000 -575)(-3000 -650);
WIRE 16 -1 (-2500 -300)(-2500 -400);
WIRE 16 -1 (-2050 -2475)(-2050 -2525);
WIRE 16 -1 (-125 -2675)(-125 -2775);
WIRE 16 -1 (-475 -1425)(-475 -1550);
WIRE 16 -1 (-2500 700)(-2500 600);
WIRE 16 -1 (-1800 75)(-1800 -25);
WIRE 16 -1 (-3300 -3075)(-3300 -3150);
WIRE 16 -1 (-125 25)(-125 -75);
WIRE 16 -1 (200 -1850)(200 -2050);
WIRE 16 -1 (200 -2050)(325 -2050);
WIRE 16 -1 (200 -2050)(200 -2075);
WIRE 16 -1 (-2725 -2800)(-2725 -2900);
WIRE 16 -1 (3125 -1950)(3150 -1950);
WIRE 16 -1 (200 850)(200 650);
WIRE 16 -1 (200 650)(325 650);
WIRE 16 -1 (200 650)(200 625);
WIRE 16 -1 (2925 750)(3075 750);
WIRE 16 -1 (-2725 -1800)(-2725 -1900);
WIRE 16 -1 (-2500 400)(-2500 225);
WIRE 16 -1 (-2500 225)(-2050 225);
FORCEPROP 2 LAST SIG_NAME P12V_E1S_0_EN_G
J 0
(-2460 235);
DISPLAY 0.595745 (-2460 235);
FORCEPROP 2 LASTPROP $XRERR UNIQUE?
J 0
(-2700 235);
DISPLAY 0.638298 (-2700 235);
PAINT MONO (-2700 235);
DISPLAY INVISIBLE (-2700 235);
WIRE 16 -1 (-2500 100)(-2500 225);
WIRE 16 -1 (4000 1400)(4000 1475);
WIRE 16 -1 (4000 1325)(4000 1400);
WIRE 16 -1 (4000 1400)(3600 1400);
WIRE 16 -1 (3600 1400)(3600 1475);
WIRE 16 -1 (3600 1400)(3175 1400);
WIRE 16 -1 (3175 1400)(3175 1475);
WIRE 16 -1 (2700 1400)(3175 1400);
WIRE 16 -1 (2700 1475)(2700 1400);
WIRE 16 -1 (4000 1675)(4000 1775);
WIRE 16 -1 (4000 1825)(4000 1775);
WIRE 16 -1 (4000 1775)(3600 1775);
WIRE 16 -1 (3600 1775)(3600 1675);
WIRE 16 -1 (3600 1775)(3175 1775);
WIRE 16 -1 (3175 1675)(3175 1775);
WIRE 16 -1 (3175 1775)(2700 1775);
WIRE 16 -1 (2700 1775)(2700 1725);
WIRE 16 -1 (2463 1775)(2700 1775);
WIRE 16 -1 (2463 1775)(2463 1150);
WIRE 16 -1 (2463 1150)(2600 1150);
WIRE 16 -1 (2275 1150)(2463 1150);
WIRE 16 -1 (2275 1075)(2275 1150);
WIRE 16 -1 (2182 1150)(2275 1150);
WIRE 16 -1 (2600 1150)(2600 1100);
WIRE 16 -1 (2182 1100)(2182 1150);
WIRE 16 -1 (1875 1150)(2182 1150);
WIRE 16 -1 (2182 1050)(2182 1100);
WIRE 16 -1 (1875 1100)(2182 1100);
WIRE 16 -1 (2182 1000)(2182 1050);
WIRE 16 -1 (1875 1050)(2182 1050);
WIRE 16 -1 (2182 950)(2182 1000);
WIRE 16 -1 (1875 1000)(2182 1000);
WIRE 16 -1 (2182 900)(2182 950);
WIRE 16 -1 (2182 950)(1875 950);
WIRE 16 -1 (2182 850)(2182 900);
WIRE 16 -1 (1875 900)(2182 900);
WIRE 16 -1 (1875 850)(2182 850);
WIRE 16 -1 (3725 1150)(3500 1150);
WIRE 16 -1 (3725 1150)(3725 1000);
WIRE 16 -1 (3500 1200)(3500 1150);
WIRE 16 -1 (3500 1150)(3300 1150);
WIRE 16 -1 (3300 1150)(3300 1000);
WIRE 16 -1 (2325 175)(2325 100);
WIRE 16 -1 (2200 100)(2325 100);
WIRE 16 -1 (2200 25)(2200 100);
WIRE 16 -1 (2100 100)(2200 100);
WIRE 16 -1 (2100 350)(2100 100);
WIRE 16 -1 (2100 100)(2050 100);
WIRE 16 -1 (2050 250)(2050 100);
WIRE 16 -1 (2000 100)(2050 100);
WIRE 16 -1 (1875 350)(2100 350);
WIRE 16 -1 (2000 200)(2000 100);
WIRE 16 -1 (1950 100)(2000 100);
WIRE 16 -1 (1875 250)(2050 250);
WIRE 16 -1 (1950 100)(1950 150);
WIRE 16 -1 (1875 200)(2000 200);
WIRE 16 -1 (1950 150)(1875 150);
WIRE 16 -1 (1075 250)(1050 250);
WIRE 16 -1 (1050 250)(1050 -50);
WIRE 16 -1 (1050 -50)(725 -50);
WIRE 16 -1 (725 -50)(725 50);
WIRE 16 -1 (725 -100)(725 -50);
WIRE 16 -1 (3775 -1025)(3775 -925);
WIRE 16 -1 (3775 -875)(3775 -925);
WIRE 16 -1 (3775 -925)(3200 -925);
WIRE 16 -1 (3200 -1025)(3200 -925);
WIRE 16 -1 (2700 -925)(3200 -925);
WIRE 16 -1 (2700 -925)(2700 -975);
WIRE 16 -1 (2470 -925)(2700 -925);
WIRE 16 -1 (2470 -925)(2470 -1550);
WIRE 16 -1 (2470 -1550)(2550 -1550);
WIRE 16 -1 (2275 -1550)(2470 -1550);
WIRE 16 -1 (2275 -1625)(2275 -1550);
WIRE 16 -1 (2182 -1550)(2275 -1550);
WIRE 16 -1 (2550 -1550)(2550 -1625);
WIRE 16 -1 (2182 -1600)(2182 -1550);
WIRE 16 -1 (1875 -1550)(2182 -1550);
WIRE 16 -1 (2182 -1650)(2182 -1600);
WIRE 16 -1 (1875 -1600)(2182 -1600);
WIRE 16 -1 (2182 -1700)(2182 -1650);
WIRE 16 -1 (1875 -1650)(2182 -1650);
WIRE 16 -1 (2182 -1750)(2182 -1700);
WIRE 16 -1 (1875 -1700)(2182 -1700);
WIRE 16 -1 (2182 -1800)(2182 -1750);
WIRE 16 -1 (2182 -1750)(1875 -1750);
WIRE 16 -1 (2182 -1850)(2182 -1800);
WIRE 16 -1 (1875 -1800)(2182 -1800);
WIRE 16 -1 (1875 -1850)(2182 -1850);
WIRE 16 -1 (3775 -1300)(3775 -1225);
WIRE 16 -1 (3775 -1375)(3775 -1300);
WIRE 16 -1 (3775 -1300)(3200 -1300);
WIRE 16 -1 (3200 -1300)(3200 -1225);
WIRE 16 -1 (2700 -1300)(3200 -1300);
WIRE 16 -1 (2700 -1225)(2700 -1300);
WIRE 16 -1 (3725 -1525)(3725 -1650);
WIRE 16 -1 (3725 -1525)(3525 -1525);
WIRE 16 -1 (3525 -1475)(3525 -1525);
WIRE 16 -1 (3325 -1525)(3525 -1525);
WIRE 16 -1 (3325 -1525)(3325 -1650);
WIRE 16 -1 (2325 -2500)(2325 -2600);
WIRE 16 -1 (2200 -2600)(2325 -2600);
WIRE 16 -1 (2200 -2675)(2200 -2600);
WIRE 16 -1 (2100 -2600)(2200 -2600);
WIRE 16 -1 (2100 -2350)(2100 -2600);
WIRE 16 -1 (2100 -2600)(2050 -2600);
WIRE 16 -1 (2050 -2450)(2050 -2600);
WIRE 16 -1 (2000 -2600)(2050 -2600);
WIRE 16 -1 (1875 -2350)(2100 -2350);
WIRE 16 -1 (2000 -2500)(2000 -2600);
WIRE 16 -1 (1950 -2600)(2000 -2600);
WIRE 16 -1 (1875 -2450)(2050 -2450);
WIRE 16 -1 (1950 -2600)(1950 -2550);
WIRE 16 -1 (1875 -2500)(2000 -2500);
WIRE 16 -1 (1950 -2550)(1875 -2550);
WIRE 16 -1 (1050 -2450)(1050 -2750);
WIRE 16 -1 (1075 -2450)(1050 -2450);
WIRE 16 -1 (1050 -2750)(725 -2750);
WIRE 16 -1 (725 -2750)(725 -2650);
WIRE 16 -1 (725 -2800)(725 -2750);
WIRE 16 -1 (-475 1600)(-700 1600);
WIRE 16 -1 (-475 1600)(-125 1600);
WIRE 16 -1 (-475 1600)(-475 1475);
WIRE 16 -1 (-700 1675)(-700 1600);
WIRE 16 -1 (-700 1600)(-900 1600);
WIRE 16 -1 (-900 1600)(-900 1525);
WIRE 16 -1 (-125 1600)(200 1600);
WIRE 16 -1 (-125 1600)(-125 1175);
WIRE 16 -1 (975 1600)(200 1600);
WIRE 16 -1 (200 1600)(200 1475);
WIRE 16 -1 (975 1600)(975 1150);
WIRE 16 -1 (975 1150)(1075 1150);
WIRE 16 -1 (975 1150)(975 1100);
WIRE 16 -1 (975 1100)(1075 1100);
WIRE 16 -1 (975 1100)(975 1050);
WIRE 16 -1 (975 1050)(1075 1050);
WIRE 16 -1 (975 1050)(975 1000);
WIRE 16 -1 (975 1000)(1075 1000);
WIRE 16 -1 (975 1000)(975 950);
WIRE 16 -1 (975 950)(1075 950);
WIRE 16 -1 (975 950)(975 900);
WIRE 16 -1 (975 900)(1075 900);
WIRE 16 -1 (975 900)(975 850);
WIRE 16 -1 (975 850)(1075 850);
WIRE 16 -1 (-475 1110)(-475 1275);
WIRE 16 -1 (-475 1110)(-700 1110);
WIRE 16 -1 (-700 1050)(-700 1110);
WIRE 16 -1 (-900 1110)(-700 1110);
WIRE 16 -1 (-900 1225)(-900 1110);
WIRE 16 -1 (-475 -1100)(-125 -1100);
WIRE 16 -1 (-475 -1100)(-475 -1225);
WIRE 16 -1 (-475 -1025)(-475 -1100);
WIRE 16 -1 (-125 -1100)(200 -1100);
WIRE 16 -1 (-125 -1100)(-125 -1475);
WIRE 16 -1 (975 -1100)(200 -1100);
WIRE 16 -1 (200 -1100)(200 -1225);
WIRE 16 -1 (975 -1100)(975 -1550);
WIRE 16 -1 (975 -1550)(1075 -1550);
WIRE 16 -1 (975 -1550)(975 -1600);
WIRE 16 -1 (975 -1600)(1075 -1600);
WIRE 16 -1 (975 -1600)(975 -1650);
WIRE 16 -1 (975 -1650)(1075 -1650);
WIRE 16 -1 (975 -1650)(975 -1700);
WIRE 16 -1 (975 -1700)(1075 -1700);
WIRE 16 -1 (975 -1700)(975 -1750);
WIRE 16 -1 (975 -1750)(1075 -1750);
WIRE 16 -1 (975 -1750)(975 -1800);
WIRE 16 -1 (975 -1800)(1075 -1800);
WIRE 16 -1 (975 -1800)(975 -1850);
WIRE 16 -1 (975 -1850)(1075 -1850);
WIRE 16 -1 (-3275 -150)(-3000 -150);
FORCEPROP 2 LAST SIG_NAME P12V_E1S_EN_0_R
J 0
(-3135 -140);
DISPLAY 0.595745 (-3135 -140);
FORCEPROP 2 LASTPROP $XRERR UNIQUE?
J 0
(-3375 -140);
DISPLAY 0.638298 (-3375 -140);
PAINT MONO (-3375 -140);
DISPLAY INVISIBLE (-3375 -140);
WIRE 16 -1 (-3000 -150)(-2750 -150);
WIRE 16 -1 (-3000 -375)(-3000 -150);
WIRE 16 -1 (-3475 -150)(-4175 -150);
FORCEPROP 2 LAST SIG_NAME E1S_0_P12V_EN
J 0
(-4110 -140);
DISPLAY 0.638298 (-4110 -140);
WIRE 16 -1 (-1800 475)(-1800 750);
WIRE 16 -1 (-1800 750)(-825 750);
FORCEPROP 2 LAST SIG_NAME P12V_E1S_UV_0_R
J 0
(-1560 760);
DISPLAY 0.574468 (-1560 760);
FORCEPROP 2 LASTPROP $XRERR UNIQUE?
J 0
(-1800 760);
DISPLAY 0.638298 (-1800 760);
PAINT MONO (-1800 760);
DISPLAY INVISIBLE (-1800 760);
WIRE 16 -1 (-125 550)(1075 550);
FORCEPROP 2 LAST SIG_NAME P12V_E1S_UV_0
J 0
(615 560);
DISPLAY 0.574468 (615 560);
FORCEPROP 2 LASTPROP $XRERR UNIQUE?
J 0
(375 560);
DISPLAY 0.638298 (375 560);
PAINT MONO (375 560);
DISPLAY INVISIBLE (375 560);
WIRE 16 -1 (-125 550)(-125 750);
WIRE 16 -1 (-125 550)(-125 500);
WIRE 16 -1 (-125 975)(-125 750);
WIRE 16 -1 (-625 750)(-125 750);
WIRE 16 -1 (175 450)(1075 450);
FORCEPROP 2 LAST SIG_NAME P12V_E1S_OV_0
J 0
(615 460);
DISPLAY 0.574468 (615 460);
FORCEPROP 2 LASTPROP $XRERR UNIQUE?
J 0
(375 460);
DISPLAY 0.638298 (375 460);
PAINT MONO (375 460);
DISPLAY INVISIBLE (375 460);
WIRE 16 -1 (175 250)(175 450);
WIRE 16 -1 (-125 250)(175 250);
WIRE 16 -1 (-125 300)(-125 250);
WIRE 16 -1 (-125 250)(-125 225);
WIRE 16 -1 (550 750)(1075 750);
FORCEPROP 2 LAST SIG_NAME P12V_E1S_VCC_0
J 0
(590 760);
DISPLAY 0.574468 (590 760);
FORCEPROP 2 LASTPROP $XRERR UNIQUE?
J 0
(350 760);
DISPLAY 0.638298 (350 760);
PAINT MONO (350 760);
DISPLAY INVISIBLE (350 760);
WIRE 16 -1 (550 1175)(550 750);
WIRE 16 -1 (550 1175)(200 1175);
WIRE 16 -1 (200 1275)(200 1175);
WIRE 16 -1 (200 1175)(200 1050);
WIRE 16 -1 (525 650)(1075 650);
FORCEPROP 2 LAST SIG_NAME P12V_E1S_REG_0
J 0
(590 660);
DISPLAY 0.574468 (590 660);
FORCEPROP 2 LASTPROP $XRERR UNIQUE?
J 0
(350 660);
DISPLAY 0.638298 (350 660);
PAINT MONO (350 660);
DISPLAY INVISIBLE (350 660);
WIRE 16 -1 (1875 550)(3300 550);
FORCEPROP 2 LAST SIG_NAME P12V_E1S_FAULT_0
J 0
(1965 560);
DISPLAY 0.574468 (1965 560);
FORCEPROP 2 LASTPROP $XRERR UNIQUE?
J 0
(1725 560);
DISPLAY 0.638298 (1725 560);
PAINT MONO (1725 560);
DISPLAY INVISIBLE (1725 560);
WIRE 16 -1 (3300 550)(3300 800);
WIRE 16 -1 (1875 650)(2850 650);
FORCEPROP 2 LAST SIG_NAME P12V_E1S_PWRGD_0
J 0
(1965 660);
DISPLAY 0.574468 (1965 660);
FORCEPROP 2 LASTPROP $XRERR UNIQUE?
J 0
(1725 660);
DISPLAY 0.638298 (1725 660);
PAINT MONO (1725 660);
DISPLAY INVISIBLE (1725 660);
WIRE 16 -1 (1875 750)(2275 750);
FORCEPROP 2 LAST SIG_NAME P12V_E1S_GATE_0
J 0
(1965 760);
DISPLAY 0.574468 (1965 760);
FORCEPROP 2 LASTPROP $XRERR UNIQUE?
J 0
(1725 760);
DISPLAY 0.638298 (1725 760);
PAINT MONO (1725 760);
DISPLAY INVISIBLE (1725 760);
WIRE 16 -1 (2600 750)(2275 750);
WIRE 16 -1 (2275 875)(2275 750);
WIRE 16 -1 (2600 900)(2600 750);
WIRE 16 -1 (2725 750)(2600 750);
WIRE 16 2175 (2700 100)(3425 100);
WIRE 16 2175 (2700 500)(2700 100);
WIRE 16 2175 (3425 500)(3425 100);
WIRE 16 2175 (2700 500)(3425 500);
WIRE 16 -1 (1875 450)(2325 450);
WIRE 16 -1 (2325 450)(2650 450);
WIRE 16 -1 (2325 375)(2325 450);
FORCEPROP 2 LAST SIG_NAME P12V_E1S_SENSE_0
J 0
(1965 460);
DISPLAY 0.574468 (1965 460);
FORCEPROP 2 LASTPROP $XRERR UNIQUE?
J 0
(1725 460);
DISPLAY 0.638298 (1725 460);
PAINT MONO (1725 460);
DISPLAY INVISIBLE (1725 460);
WIRE 16 -1 (2650 450)(3000 450);
WIRE 16 -1 (2650 450)(2650 225);
WIRE 16 -1 (2650 225)(3000 225);
WIRE 16 -1 (3200 450)(4200 450);
FORCEPROP 2 LAST SIG_NAME P12V_E1S_0_ISENSE_MAM_MAM
J 0
(3515 460);
DISPLAY 0.574468 (3515 460);
WIRE 16 -1 (3725 800)(3725 650);
FORCEPROP 2 LAST SIG_NAME HP_LVC3_E1S_0_HSC_PWRGD
J 0
(3565 660);
DISPLAY 0.574468 (3565 660);
WIRE 16 -1 (3725 650)(4200 650);
WIRE 16 -1 (3050 650)(3725 650);
WIRE 16 -1 (3200 225)(4200 225);
FORCEPROP 2 LAST SIG_NAME P12V_E1S_0_ISENSE_MAM_TIC
J 0
(3515 235);
DISPLAY 0.574468 (3515 235);
WIRE 16 -1 (-3550 -2650)(-3300 -2650);
FORCEPROP 2 LAST SIG_NAME P3V3_E1S_EN_0_R
J 0
(-3385 -2640);
DISPLAY 0.595745 (-3385 -2640);
FORCEPROP 2 LASTPROP $XRERR UNIQUE?
J 0
(-3625 -2640);
DISPLAY 0.638298 (-3625 -2640);
PAINT MONO (-3625 -2640);
DISPLAY INVISIBLE (-3625 -2640);
WIRE 16 -1 (-3300 -2650)(-2975 -2650);
WIRE 16 -1 (-3300 -2875)(-3300 -2650);
WIRE 16 -1 (-2725 -2400)(-2725 -2325);
WIRE 16 -1 (-2725 -2325)(-2300 -2325);
FORCEPROP 2 LAST SIG_NAME P3V3_E1S_0_EN_G
J 0
(-2685 -2315);
DISPLAY 0.595745 (-2685 -2315);
FORCEPROP 2 LASTPROP $XRERR UNIQUE?
J 0
(-2925 -2315);
DISPLAY 0.638298 (-2925 -2315);
PAINT MONO (-2925 -2315);
DISPLAY INVISIBLE (-2925 -2315);
WIRE 16 -1 (-2725 -2100)(-2725 -2325);
WIRE 16 -1 (-700 -1950)(-2050 -1950);
FORCEPROP 2 LAST SIG_NAME P3V3_E1S_UV_0_R
J 0
(-1310 -1940);
DISPLAY 0.574468 (-1310 -1940);
FORCEPROP 2 LASTPROP $XRERR UNIQUE?
J 0
(-1550 -1940);
DISPLAY 0.638298 (-1550 -1940);
PAINT MONO (-1550 -1940);
DISPLAY INVISIBLE (-1550 -1940);
WIRE 16 -1 (-2050 -2075)(-2050 -1950);
WIRE 16 -1 (-125 -2150)(1075 -2150);
FORCEPROP 2 LAST SIG_NAME P3V3_E1S_UV_0
J 0
(615 -2140);
DISPLAY 0.574468 (615 -2140);
FORCEPROP 2 LASTPROP $XRERR UNIQUE?
J 0
(375 -2140);
DISPLAY 0.638298 (375 -2140);
PAINT MONO (375 -2140);
DISPLAY INVISIBLE (375 -2140);
WIRE 16 -1 (-125 -2150)(-125 -1950);
WIRE 16 -1 (-125 -2150)(-125 -2200);
WIRE 16 -1 (-125 -1675)(-125 -1950);
WIRE 16 -1 (-500 -1950)(-125 -1950);
WIRE 16 -1 (550 -1525)(550 -1950);
WIRE 16 -1 (550 -1525)(200 -1525);
WIRE 16 -1 (550 -1950)(1075 -1950);
FORCEPROP 2 LAST SIG_NAME P3V3_E1S_VCC_0
J 0
(590 -1940);
DISPLAY 0.574468 (590 -1940);
FORCEPROP 2 LASTPROP $XRERR UNIQUE?
J 0
(350 -1940);
DISPLAY 0.638298 (350 -1940);
PAINT MONO (350 -1940);
DISPLAY INVISIBLE (350 -1940);
WIRE 16 -1 (200 -1425)(200 -1525);
WIRE 16 -1 (200 -1525)(200 -1650);
WIRE 16 -1 (175 -2250)(1075 -2250);
FORCEPROP 2 LAST SIG_NAME P3V3_E1S_OV_0
J 0
(615 -2240);
DISPLAY 0.574468 (615 -2240);
FORCEPROP 2 LASTPROP $XRERR UNIQUE?
J 0
(375 -2240);
DISPLAY 0.638298 (375 -2240);
PAINT MONO (375 -2240);
DISPLAY INVISIBLE (375 -2240);
WIRE 16 -1 (175 -2450)(175 -2250);
WIRE 16 -1 (-125 -2450)(175 -2450);
WIRE 16 -1 (-125 -2400)(-125 -2450);
WIRE 16 -1 (-125 -2450)(-125 -2475);
WIRE 16 -1 (525 -2050)(1075 -2050);
FORCEPROP 2 LAST SIG_NAME P3V3_E1S_REG_0
J 0
(590 -2040);
DISPLAY 0.574468 (590 -2040);
FORCEPROP 2 LASTPROP $XRERR UNIQUE?
J 0
(350 -2040);
DISPLAY 0.638298 (350 -2040);
PAINT MONO (350 -2040);
DISPLAY INVISIBLE (350 -2040);
WIRE 16 -1 (1875 -1950)(2275 -1950);
FORCEPROP 2 LAST SIG_NAME P3V3_E1S_GATE_0
J 0
(1965 -1940);
DISPLAY 0.574468 (1965 -1940);
FORCEPROP 2 LASTPROP $XRERR UNIQUE?
J 0
(1725 -1940);
DISPLAY 0.638298 (1725 -1940);
PAINT MONO (1725 -1940);
DISPLAY INVISIBLE (1725 -1940);
WIRE 16 -1 (2550 -1950)(2275 -1950);
WIRE 16 -1 (2275 -1825)(2275 -1950);
WIRE 16 -1 (2925 -1950)(2550 -1950);
WIRE 16 -1 (2550 -1825)(2550 -1950);
WIRE 16 -1 (1075 -2350)(725 -2350);
FORCEPROP 2 LAST SIG_NAME P3V3_E1S_CB_0
J 0
(615 -2340);
DISPLAY 0.574468 (615 -2340);
FORCEPROP 2 LASTPROP $XRERR UNIQUE?
J 0
(375 -2340);
DISPLAY 0.638298 (375 -2340);
PAINT MONO (375 -2340);
DISPLAY INVISIBLE (375 -2340);
WIRE 16 -1 (725 -2350)(725 -2450);
WIRE 16 -1 (1875 -2050)(2875 -2050);
FORCEPROP 2 LAST SIG_NAME P3V3_E1S_PWRGD_0
J 0
(1965 -2040);
DISPLAY 0.574468 (1965 -2040);
FORCEPROP 2 LASTPROP $XRERR UNIQUE?
J 0
(1725 -2040);
DISPLAY 0.638298 (1725 -2040);
PAINT MONO (1725 -2040);
DISPLAY INVISIBLE (1725 -2040);
WIRE 16 -1 (1875 -2150)(3325 -2150);
FORCEPROP 2 LAST SIG_NAME P3V3_E1S_FAULT_0
J 0
(1965 -2140);
DISPLAY 0.574468 (1965 -2140);
FORCEPROP 2 LASTPROP $XRERR UNIQUE?
J 0
(1725 -2140);
DISPLAY 0.638298 (1725 -2140);
PAINT MONO (1725 -2140);
DISPLAY INVISIBLE (1725 -2140);
WIRE 16 -1 (3325 -2150)(3325 -1850);
WIRE 16 -1 (3075 -2050)(3725 -2050);
FORCEPROP 2 LAST SIG_NAME P3V3_E1S_PWRGD_0_R
J 0
(3490 -2040);
DISPLAY 0.510638 (3490 -2040);
PAINT WHITE (3490 -2040);
WIRE 16 -1 (3725 -1850)(3725 -2050);
WIRE 16 -1 (3725 -2050)(3975 -2050);
WIRE 16 -1 (2325 -2300)(2325 -2250);
FORCEPROP 2 LAST SIG_NAME P3V3_E1S_SENSE_0
J 0
(1965 -2240);
DISPLAY 0.574468 (1965 -2240);
FORCEPROP 2 LASTPROP $XRERR UNIQUE?
J 0
(1725 -2240);
DISPLAY 0.638298 (1725 -2240);
PAINT MONO (1725 -2240);
DISPLAY INVISIBLE (1725 -2240);
WIRE 16 -1 (1875 -2250)(2325 -2250);
WIRE 16 -1 (-4350 -2650)(-3750 -2650);
FORCEPROP 2 LAST SIG_NAME E1S_0_P3V3_EN
J 0
(-4260 -2640);
DISPLAY 0.638298 (-4260 -2640);
WIRE 16 2175 (-4400 2125)(-2697 2125);
WIRE 16 2175 (-4400 3025)(-4400 2125);
WIRE 16 2175 (-2697 3025)(-2697 2125);
WIRE 16 2175 (-4400 3025)(-2697 3025);
WIRE 16 -1 (1075 350)(725 350);
FORCEPROP 2 LAST SIG_NAME P12V_E1S_CB_0
J 0
(615 360);
DISPLAY 0.574468 (615 360);
FORCEPROP 2 LASTPROP $XRERR UNIQUE?
J 0
(375 360);
DISPLAY 0.638298 (375 360);
PAINT MONO (375 360);
DISPLAY INVISIBLE (375 360);
WIRE 16 -1 (725 350)(725 250);
DOT 1 (-125 -2150);
DOT 1 (200 -1525);
DOT 1 (975 -1600);
DOT 1 (3525 -1525);
DOT 1 (3775 -1300);
DOT 1 (2182 -1700);
DOT 1 (2182 -1800);
DOT 1 (2275 -1550);
DOT 1 (2050 -2600);
DOT 1 (4000 1775);
DOT 1 (4000 1400);
DOT 1 (3600 1775);
DOT 1 (3600 1400);
DOT 1 (3175 1775);
DOT 1 (3725 650);
DOT 1 (2182 1000);
DOT 1 (2650 450);
DOT 1 (2275 750);
DOT 1 (2200 100);
DOT 1 (2100 100);
DOT 1 (2050 100);
DOT 1 (2000 100);
DOT 1 (975 1050);
DOT 1 (975 950);
DOT 1 (975 900);
DOT 1 (200 1175);
DOT 1 (3775 -925);
DOT 1 (3725 -2050);
DOT 1 (2700 -925);
DOT 1 (2182 -1650);
DOT 1 (2200 -2600);
DOT 1 (2100 -2600);
DOT 1 (200 -1100);
DOT 1 (975 -1750);
DOT 1 (975 -1800);
DOT 1 (2000 -2600);
DOT 1 (725 -2750);
DOT 1 (-125 1600);
DOT 1 (-475 1600);
DOT 1 (-700 1600);
DOT 1 (-125 750);
DOT 1 (-125 550);
DOT 1 (-125 250);
DOT 1 (-2500 225);
DOT 1 (-3000 -150);
DOT 1 (-125 -1100);
DOT 1 (-475 -1100);
DOT 1 (-125 -1950);
DOT 1 (-125 -2450);
DOT 1 (-3300 -2650);
DOT 1 (2182 -1750);
DOT 1 (2182 -1600);
DOT 1 (200 -2050);
DOT 1 (975 -1650);
DOT 1 (2275 -1950);
DOT 1 (2550 -1950);
DOT 1 (2470 -1550);
DOT 1 (975 -1550);
DOT 1 (2182 -1550);
DOT 1 (975 -1700);
DOT 1 (-2725 -2325);
DOT 1 (3200 -1300);
DOT 1 (3200 -925);
DOT 1 (2700 1775);
DOT 1 (2182 950);
DOT 1 (2275 1150);
DOT 1 (3175 1400);
DOT 1 (2600 750);
DOT 1 (2182 1050);
DOT 1 (2325 450);
DOT 1 (2182 900);
DOT 1 (2182 1150);
DOT 1 (3500 1150);
DOT 1 (725 -50);
DOT 1 (975 1000);
DOT 1 (2182 1100);
DOT 1 (200 650);
DOT 1 (975 1100);
DOT 1 (2463 1150);
DOT 1 (975 1150);
DOT 1 (-700 1110);
DOT 1 (200 1600);
FORCENOTE
START UP TIME:3.94MS
(2775 -2350) 0;
DISPLAY LEFT (2775 -2350);
DISPLAY 1.021277 (2775 -2350);
PAINT WHITE (2775 -2350);
FORCENOTE
VIMON(MAX)= 1.641V @ IOUT=2.79A
(975 -400) 0;
DISPLAY LEFT (975 -400);
DISPLAY 1.021277 (975 -400);
PAINT WHITE (975 -400);
FORCENOTE
P3V3_E1S_0_R
(-4350 2475) 0;
DISPLAY LEFT (-4350 2475);
DISPLAY 1.021277 (-4350 2475);
FORCENOTE
OCP=MAX*1.3=2.71A
(-4350 2700) 0;
DISPLAY LEFT (-4350 2700);
DISPLAY 1.021277 (-4350 2700);
FORCENOTE
IMAX=2.083A
(-4350 2775) 0;
DISPLAY LEFT (-4350 2775);
DISPLAY 1.021277 (-4350 2775);
FORCENOTE
P12V_E1S_0
(-4350 2850) 0;
DISPLAY LEFT (-4350 2850);
DISPLAY 1.021277 (-4350 2850);
FORCENOTE
OCP=0.75A
(-4350 2325) 0;
DISPLAY LEFT (-4350 2325);
DISPLAY 1.021277 (-4350 2325);
FORCENOTE
IMAX=0.025A
(-4350 2400) 0;
DISPLAY LEFT (-4350 2400);
DISPLAY 1.021277 (-4350 2400);
FORCENOTE
DESIGN SPECIFICATION
(-4363 2944) 0;
DISPLAY LEFT (-4363 2944);
DISPLAY 1.170213 (-4363 2944);
FORCENOTE
VIMON(MAX)= 1.604V @ IOUT=0.75A
(925 -2950) 0;
DISPLAY LEFT (925 -2950);
DISPLAY 1.021277 (925 -2950);
PAINT WHITE (925 -2950);
FORCENOTE
OVP: 3.89V
(-650 -2325) 0;
DISPLAY LEFT (-650 -2325);
DISPLAY 1.021277 (-650 -2325);
PAINT WHITE (-650 -2325);
FORCENOTE
UVP: 2.63V
(-650 -2250) 0;
DISPLAY LEFT (-650 -2250);
DISPLAY 1.021277 (-650 -2250);
PAINT WHITE (-650 -2250);
FORCENOTE
START UP TIME:8.21MS
(3375 525) 0;
DISPLAY LEFT (3375 525);
DISPLAY 1.021277 (3375 525);
PAINT WHITE (3375 525);
FORCENOTE
OVP: 14.91V
(-700 425) 0;
DISPLAY LEFT (-700 425);
DISPLAY 1.021277 (-700 425);
PAINT WHITE (-700 425);
FORCENOTE
UVP: 10.17V
(-700 500) 0;
DISPLAY LEFT (-700 500);
DISPLAY 1.021277 (-700 500);
PAINT WHITE (-700 500);
QUIT
